{ Packager-XL run on 25-Aug-2023 AT 17:03:33 }
FILE_TYPE = BACK_ANNOTATION;
DRAWING = "@scm_lib.scm(sch_1):page10";
BODY = "Q_RES","I293": #LOCATION = "R243" !CDS_LOCATION = "R243" #SEC = "1" !CDS_SEC = "1";
"A":   PN = "1"  !CDS_PN = "1";
"B":   PN = "2"  !CDS_PN = "2";
BODY = "Q_RES","I456": #LOCATION = "R822" !CDS_LOCATION = "R822" &SEC = "1" #&CDS_SEC = "1";
"A":   PN = "1"  !CDS_PN = "1";
"B":   PN = "2"  !CDS_PN = "2";
BODY = "Q_RES","I458": #LOCATION = "R36" !CDS_LOCATION = "R36" #SEC = "1" !CDS_SEC = "1";
"A":   PN = "1"  !CDS_PN = "1";
"B":   PN = "2"  !CDS_PN = "2";
BODY = "Q_RES","I459": #LOCATION = "R46" !CDS_LOCATION = "R46" #SEC = "1" !CDS_SEC = "1";
"A":   PN = "1"  !CDS_PN = "1";
"B":   PN = "2"  !CDS_PN = "2";
BODY = "Q_CAP","I503": #LOCATION = "C174" !CDS_LOCATION = "C174" #SEC = "1" !CDS_SEC = "1";
"A":   PN = "1"  !CDS_PN = "1";
"B":   PN = "2"  !CDS_PN = "2";
BODY = "FCONN168_ME1016810202011_SCM","I553": LOCATION = "GF1" #&CDS_LOCATION = "GF1" &SEC = "1" #&CDS_SEC = "1";
"CHASI_N":   PN = "A54"  !CDS_PN = "A54";
"CLK_100M_PCIE_DN":   PN = "A15"  !CDS_PN = "A15";
"CLK_100M_PCIE_DP":   PN = "A14"  !CDS_PN = "A14";
"DBP_PRDY_N":   PN = "A50"  !CDS_PN = "A50";
"DBP_PREQ_N":   PN = "A49"  !CDS_PN = "A49";
"ESPI_ALERT_N":   PN = "B3"  !CDS_PN = "B3";
"ESPI_CLK":   PN = "B1"  !CDS_PN = "B1";
"ESPI_CS0_N":   PN = "B2"  !CDS_PN = "B2";
"ESPI_IO0":   PN = "B5"  !CDS_PN = "B5";
"ESPI_IO1":   PN = "B6"  !CDS_PN = "B6";
"ESPI_IO2":   PN = "B7"  !CDS_PN = "B7";
"ESPI_IO3":   PN = "B8"  !CDS_PN = "B8";
"ESPI_RESET_N":   PN = "B4"  !CDS_PN = "B4";
"GND_A13":   PN = "A13"  !CDS_PN = "A13";
"GND_A16":   PN = "A16"  !CDS_PN = "A16";
"GND_A19":   PN = "A19"  !CDS_PN = "A19";
"GND_A22":   PN = "A22"  !CDS_PN = "A22";
"GND_A33":   PN = "A33"  !CDS_PN = "A33";
"GND_A42":   PN = "A42"  !CDS_PN = "A42";
"GND_A58":   PN = "A58"  !CDS_PN = "A58";
"GND_A61":   PN = "A61"  !CDS_PN = "A61";
"GND_A64":   PN = "A64"  !CDS_PN = "A64";
"GND_A67":   PN = "A67"  !CDS_PN = "A67";
"GND_A70":   PN = "A70"  !CDS_PN = "A70";
"GND_B10":   PN = "B10"  !CDS_PN = "B10";
"GND_B17":   PN = "B17"  !CDS_PN = "B17";
"GND_B26":   PN = "B26"  !CDS_PN = "B26";
"GND_B33":   PN = "B33"  !CDS_PN = "B33";
"GND_B38":   PN = "B38"  !CDS_PN = "B38";
"GND_B49":   PN = "B49"  !CDS_PN = "B49";
"GND_B52":   PN = "B52"  !CDS_PN = "B52";
"GND_B55":   PN = "B55"  !CDS_PN = "B55";
"GND_B58":   PN = "B58"  !CDS_PN = "B58";
"GND_B61":   PN = "B61"  !CDS_PN = "B61";
"GND_B64":   PN = "B64"  !CDS_PN = "B64";
"GND_B67":   PN = "B67"  !CDS_PN = "B67";
"GND_B70":   PN = "B70"  !CDS_PN = "B70";
"GND_OA3":   PN = "OA3"  !CDS_PN = "OA3";
"GND_OA4":   PN = "OA4"  !CDS_PN = "OA4";
"GND_OA13":   PN = "OA13"  !CDS_PN = "OA13";
"GND_OB4":   PN = "OB4"  !CDS_PN = "OB4";
"GND_OB7":   PN = "OB7"  !CDS_PN = "OB7";
"GND_OB10":   PN = "OB10"  !CDS_PN = "OB10";
"HPM_FW_RECOVERY":   PN = "A43"  !CDS_PN = "A43";
"HPM_STBY_EN":   PN = "A45"  !CDS_PN = "A45";
"HPM_STBY_RDY":   PN = "A44"  !CDS_PN = "A44";
"HPM_STBY_RST_N":   PN = "A46"  !CDS_PN = "A46";
"I2C_0_SCL":   PN = "A1"  !CDS_PN = "A1";
"I2C_0_SDA":   PN = "A2"  !CDS_PN = "A2";
"I2C_1_SCL":   PN = "A3"  !CDS_PN = "A3";
"I2C_1_SDA":   PN = "A4"  !CDS_PN = "A4";
"I2C_2_SCL":   PN = "A5"  !CDS_PN = "A5";
"I2C_2_SDA":   PN = "A6"  !CDS_PN = "A6";
"I2C_3_SCL":   PN = "A7"  !CDS_PN = "A7";
"I2C_3_SDA":   PN = "A8"  !CDS_PN = "A8";
"I2C_4_SCL":   PN = "A9"  !CDS_PN = "A9";
"I2C_4_SDA":   PN = "A10"  !CDS_PN = "A10";
"I2C_5_SCL":   PN = "A11"  !CDS_PN = "A11";
"I2C_5_SDA":   PN = "A12"  !CDS_PN = "A12";
"I2C_6_SCL":   PN = "A23"  !CDS_PN = "A23";
"I2C_6_SDA":   PN = "A24"  !CDS_PN = "A24";
"I2C_7_SCL":   PN = "A25"  !CDS_PN = "A25";
"I2C_7_SDA":   PN = "A26"  !CDS_PN = "A26";
"I2C_8_SCL":   PN = "A27"  !CDS_PN = "A27";
"I2C_8_SDA":   PN = "A28"  !CDS_PN = "A28";
"I2C_9_SCL":   PN = "A29"  !CDS_PN = "A29";
"I2C_9_SDA":   PN = "A30"  !CDS_PN = "A30";
"I2C_10_SCL":   PN = "A31"  !CDS_PN = "A31";
"I2C_10_SDA":   PN = "A32"  !CDS_PN = "A32";
"I2C_11_SCL":   PN = "A38"  !CDS_PN = "A38";
"I2C_11_SDA":   PN = "A39"  !CDS_PN = "A39";
"I2C_12_SCL":   PN = "A40"  !CDS_PN = "A40";
"I2C_12_SDA":   PN = "A41"  !CDS_PN = "A41";
"I3C_0_SCL":   PN = "OA5"  !CDS_PN = "OA5";
"I3C_0_SDA":   PN = "OA6"  !CDS_PN = "OA6";
"I3C_1_SCL":   PN = "OA7"  !CDS_PN = "OA7";
"I3C_1_SDA":   PN = "OA8"  !CDS_PN = "OA8";
"I3C_2_SCL":   PN = "OA9"  !CDS_PN = "OA9";
"I3C_2_SDA":   PN = "OA10"  !CDS_PN = "OA10";
"I3C_3_SCL":   PN = "OA11"  !CDS_PN = "OA11";
"I3C_3_SDA":   PN = "OA12"  !CDS_PN = "OA12";
"IRQ_N":   PN = "A56"  !CDS_PN = "A56";
"JTAG_TCK":   PN = "A34"  !CDS_PN = "A34";
"JTAG_TDI":   PN = "A36"  !CDS_PN = "A36";
"JTAG_TDO":   PN = "A37"  !CDS_PN = "A37";
"JTAG_TMS":   PN = "A35"  !CDS_PN = "A35";
"NCSI_CLK":   PN = "B18"  !CDS_PN = "B18";
"NCSI_CRS_DV":   PN = "B19"  !CDS_PN = "B19";
"NCSI_RXD0":   PN = "B24"  !CDS_PN = "B24";
"NCSI_RXD1":   PN = "B25"  !CDS_PN = "B25";
"NCSI_RXER":   PN = "B23"  !CDS_PN = "B23";
"NCSI_TXD0":   PN = "B21"  !CDS_PN = "B21";
"NCSI_TXD1":   PN = "B22"  !CDS_PN = "B22";
"NCSI_TXEN":   PN = "B20"  !CDS_PN = "B20";
"P3V0_BAT":   PN = "B41"  !CDS_PN = "B41";
"P12V_AUX_OA1":   PN = "OA1"  !CDS_PN = "OA1";
"P12V_AUX_OA2":   PN = "OA2"  !CDS_PN = "OA2";
"P12V_AUX_OB1":   PN = "OB1"  !CDS_PN = "OB1";
"P12V_AUX_OB2":   PN = "OB2"  !CDS_PN = "OB2";
"PCIE_BMC_RX_DN":   PN = "A21"  !CDS_PN = "A21";
"PCIE_BMC_RX_DP":   PN = "A20"  !CDS_PN = "A20";
"PCIE_BMC_TX_DN":   PN = "A18"  !CDS_PN = "A18";
"PCIE_BMC_TX_DP":   PN = "A17"  !CDS_PN = "A17";
"PCIE_HPM_RXN_0":   PN = "A60"  !CDS_PN = "A60";
"PCIE_HPM_RXN_1":   PN = "A63"  !CDS_PN = "A63";
"PCIE_HPM_RXN_2":   PN = "A66"  !CDS_PN = "A66";
"PCIE_HPM_RXN_3":   PN = "A69"  !CDS_PN = "A69";
"PCIE_HPM_RXP_0":   PN = "A59"  !CDS_PN = "A59";
"PCIE_HPM_RXP_1":   PN = "A62"  !CDS_PN = "A62";
"PCIE_HPM_RXP_2":   PN = "A65"  !CDS_PN = "A65";
"PCIE_HPM_RXP_3":   PN = "A68"  !CDS_PN = "A68";
"PCIE_HPM_TXN_0":   PN = "B60"  !CDS_PN = "B60";
"PCIE_HPM_TXN_1":   PN = "B63"  !CDS_PN = "B63";
"PCIE_HPM_TXN_2":   PN = "B66"  !CDS_PN = "B66";
"PCIE_HPM_TXN_3":   PN = "B69"  !CDS_PN = "B69";
"PCIE_HPM_TXP_0":   PN = "B59"  !CDS_PN = "B59";
"PCIE_HPM_TXP_1":   PN = "B62"  !CDS_PN = "B62";
"PCIE_HPM_TXP_2":   PN = "B65"  !CDS_PN = "B65";
"PCIE_HPM_TXP_3":   PN = "B68"  !CDS_PN = "B68";
"PECI_BMC":   PN = "B27"  !CDS_PN = "B27";
"PRSNT0_N":   PN = "OB3"  !CDS_PN = "OB3";
"PRSNT1_N":   PN = "A57"  !CDS_PN = "A57";
"PVCCIO_PECI":   PN = "B28"  !CDS_PN = "B28";
"QSPI0_CLK":   PN = "B11"  !CDS_PN = "B11";
"QSPI0_CS0_N":   PN = "B12"  !CDS_PN = "B12";
"QSPI0_CS1_N":   PN = "B42"  !CDS_PN = "B42";
"QSPI0_D0":   PN = "B13"  !CDS_PN = "B13";
"QSPI0_D1":   PN = "B14"  !CDS_PN = "B14";
"QSPI0_D2":   PN = "B15"  !CDS_PN = "B15";
"QSPI0_D3":   PN = "B16"  !CDS_PN = "B16";
"QSPI1_CLK":   PN = "B43"  !CDS_PN = "B43";
"QSPI1_CS0_N":   PN = "B44"  !CDS_PN = "B44";
"QSPI1_D0":   PN = "B45"  !CDS_PN = "B45";
"QSPI1_D1":   PN = "B46"  !CDS_PN = "B46";
"QSPI1_D2":   PN = "B47"  !CDS_PN = "B47";
"QSPI1_D3":   PN = "B48"  !CDS_PN = "B48";
"ROT_CPU_RST_N":   PN = "A53"  !CDS_PN = "A53";
"RST_PLTRST_BUF_N":   PN = "A51"  !CDS_PN = "A51";
"RSVD0":   PN = "B56"  !CDS_PN = "B56";
"RSVD1":   PN = "B57"  !CDS_PN = "B57";
"RSVD2":   PN = "B35"  !CDS_PN = "B35";
"RSVD3":   PN = "B9"  !CDS_PN = "B9";
"SGPIO0_DI":   PN = "B31"  !CDS_PN = "B31";
"SGPIO0_DO":   PN = "B29"  !CDS_PN = "B29";
"SGPIO0_LD":   PN = "B32"  !CDS_PN = "B32";
"SGPIO1_DI":   PN = "B36"  !CDS_PN = "B36";
"SGPIO1_DO":   PN = "B34"  !CDS_PN = "B34";
"SGPIO1_LD":   PN = "B37"  !CDS_PN = "B37";
"SGPIO_CLK":   PN = "B30"  !CDS_PN = "B30";
"SGPIO_INTR_N":   PN = "B40"  !CDS_PN = "B40";
"SGPIO_RESET_N":   PN = "B39"  !CDS_PN = "B39";
"SPARE0":   PN = "A55"  !CDS_PN = "A55";
"SPARE1":   PN = "A52"  !CDS_PN = "A52";
"SPI0_CLK":   PN = "OB11"  !CDS_PN = "OB11";
"SPI0_CS_N":   PN = "OB12"  !CDS_PN = "OB12";
"SPI0_MISO":   PN = "OB14"  !CDS_PN = "OB14";
"SPI0_MOSI":   PN = "OB13"  !CDS_PN = "OB13";
"SYS_PWRBTN_N":   PN = "A47"  !CDS_PN = "A47";
"SYS_PWROK":   PN = "A48"  !CDS_PN = "A48";
"UART0_SCM_RX":   PN = "OB9"  !CDS_PN = "OB9";
"UART0_SCM_TX":   PN = "OB8"  !CDS_PN = "OB8";
"UART1_SCM_RX":   PN = "OB6"  !CDS_PN = "OB6";
"UART1_SCM_TX":   PN = "OB5"  !CDS_PN = "OB5";
"USB1_DN":   PN = "B54"  !CDS_PN = "B54";
"USB1_DP":   PN = "B53"  !CDS_PN = "B53";
"USB2_DN":   PN = "B51"  !CDS_PN = "B51";
"USB2_DP":   PN = "B50"  !CDS_PN = "B50";
"VIRTUAL_RESEAT":   PN = "OA14"  !CDS_PN = "OA14";
BODY = "Q_RES","I557": LOCATION = "R455" #&CDS_LOCATION = "R455" &SEC = "1" #&CDS_SEC = "1";
"A":   PN = "1"  !CDS_PN = "1";
"B":   PN = "2"  !CDS_PN = "2";
BODY = "Q_RES","I562": LOCATION = "R564" #&CDS_LOCATION = "R564" &SEC = "1" #&CDS_SEC = "1";
"A":   PN = "1"  !CDS_PN = "1";
"B":   PN = "2"  !CDS_PN = "2";
BODY = "Q_RES","I565": LOCATION = "R811" #&CDS_LOCATION = "R811" &SEC = "1" #&CDS_SEC = "1";
"A":   PN = "1"  !CDS_PN = "1";
"B":   PN = "2"  !CDS_PN = "2";
BODY = "Q_RES","I568": LOCATION = "R838" #&CDS_LOCATION = "R838" &SEC = "1" #&CDS_SEC = "1";
"A":   PN = "1"  !CDS_PN = "1";
"B":   PN = "2"  !CDS_PN = "2";
BODY = "Q_RES","I569": LOCATION = "R847" #&CDS_LOCATION = "R847" &SEC = "1" #&CDS_SEC = "1";
"A":   PN = "1"  !CDS_PN = "1";
"B":   PN = "2"  !CDS_PN = "2";
BODY = "Q_CAP","I573": #LOCATION = "C329" !CDS_LOCATION = "C329" &SEC = "1" #&CDS_SEC = "1";
"A":   PN = "1"  !CDS_PN = "1";
"B":   PN = "2"  !CDS_PN = "2";
BODY = "Q_CAP","I574": #LOCATION = "C330" !CDS_LOCATION = "C330" &SEC = "1" #&CDS_SEC = "1";
"A":   PN = "1"  !CDS_PN = "1";
"B":   PN = "2"  !CDS_PN = "2";
DRAWING = "@scm_lib.scm(sch_1):page11";
BODY = "Q_RES","I110": #LOCATION = "R75" !CDS_LOCATION = "R75" &SEC = "1" #&CDS_SEC = "1";
"A":   PN = "1"  !CDS_PN = "1";
"B":   PN = "2"  !CDS_PN = "2";
BODY = "Q_RES","I117": #LOCATION = "R74" !CDS_LOCATION = "R74" &SEC = "1" #&CDS_SEC = "1";
"A":   PN = "1"  !CDS_PN = "1";
"B":   PN = "2"  !CDS_PN = "2";
BODY = "Q_RES","I118": #LOCATION = "R73" !CDS_LOCATION = "R73" &SEC = "1" #&CDS_SEC = "1";
"A":   PN = "1"  !CDS_PN = "1";
"B":   PN = "2"  !CDS_PN = "2";
BODY = "Q_RES","I128": #LOCATION = "R77" !CDS_LOCATION = "R77" &SEC = "1" #&CDS_SEC = "1";
"A":   PN = "1"  !CDS_PN = "1";
"B":   PN = "2"  !CDS_PN = "2";
BODY = "Q_RES","I129": #LOCATION = "R78" !CDS_LOCATION = "R78" &SEC = "1" #&CDS_SEC = "1";
"A":   PN = "1"  !CDS_PN = "1";
"B":   PN = "2"  !CDS_PN = "2";
BODY = "Q_RES","I130": #LOCATION = "R79" !CDS_LOCATION = "R79" &SEC = "1" #&CDS_SEC = "1";
"A":   PN = "1"  !CDS_PN = "1";
"B":   PN = "2"  !CDS_PN = "2";
BODY = "Q_RES","I171": #LOCATION = "R40" !CDS_LOCATION = "R40" &SEC = "1" #&CDS_SEC = "1";
"A":   PN = "1"  !CDS_PN = "1";
"B":   PN = "2"  !CDS_PN = "2";
BODY = "Q_RES","I175": #LOCATION = "R44" !CDS_LOCATION = "R44" &SEC = "1" #&CDS_SEC = "1";
"A":   PN = "1"  !CDS_PN = "1";
"B":   PN = "2"  !CDS_PN = "2";
BODY = "Q_RES","I176": #LOCATION = "R45" !CDS_LOCATION = "R45" &SEC = "1" #&CDS_SEC = "1";
"A":   PN = "1"  !CDS_PN = "1";
"B":   PN = "2"  !CDS_PN = "2";
BODY = "Q_RES","I179": #LOCATION = "R68" !CDS_LOCATION = "R68" &SEC = "1" #&CDS_SEC = "1";
"A":   PN = "1"  !CDS_PN = "1";
"B":   PN = "2"  !CDS_PN = "2";
BODY = "Q_RES","I181": #LOCATION = "R66" !CDS_LOCATION = "R66" &SEC = "1" #&CDS_SEC = "1";
"A":   PN = "1"  !CDS_PN = "1";
"B":   PN = "2"  !CDS_PN = "2";
BODY = "Q_RES","I194": #LOCATION = "R34" !CDS_LOCATION = "R34" &SEC = "1" #&CDS_SEC = "1";
"A":   PN = "1"  !CDS_PN = "1";
"B":   PN = "2"  !CDS_PN = "2";
BODY = "Q_RES","I212": #LOCATION = "R163" !CDS_LOCATION = "R163" &SEC = "1" #&CDS_SEC = "1";
"A":   PN = "1"  !CDS_PN = "1";
"B":   PN = "2"  !CDS_PN = "2";
BODY = "Q_RES","I214": #LOCATION = "R101" !CDS_LOCATION = "R101" &SEC = "1" #&CDS_SEC = "1";
"A":   PN = "1"  !CDS_PN = "1";
"B":   PN = "2"  !CDS_PN = "2";
BODY = "Q_RES","I218": #LOCATION = "R161" !CDS_LOCATION = "R161" &SEC = "1" #&CDS_SEC = "1";
"A":   PN = "1"  !CDS_PN = "1";
"B":   PN = "2"  !CDS_PN = "2";
BODY = "Q_RES","I219": #LOCATION = "R103" !CDS_LOCATION = "R103" &SEC = "1" #&CDS_SEC = "1";
"A":   PN = "1"  !CDS_PN = "1";
"B":   PN = "2"  !CDS_PN = "2";
BODY = "Q_RES","I225": #LOCATION = "R41" !CDS_LOCATION = "R41" &SEC = "1" #&CDS_SEC = "1";
"A":   PN = "1"  !CDS_PN = "1";
"B":   PN = "2"  !CDS_PN = "2";
BODY = "Q_RES","I227": #LOCATION = "R69" !CDS_LOCATION = "R69" &SEC = "1" #&CDS_SEC = "1";
"A":   PN = "1"  !CDS_PN = "1";
"B":   PN = "2"  !CDS_PN = "2";
BODY = "Q_RES","I230": #LOCATION = "R76" !CDS_LOCATION = "R76" &SEC = "1" #&CDS_SEC = "1";
"A":   PN = "1"  !CDS_PN = "1";
"B":   PN = "2"  !CDS_PN = "2";
BODY = "Q_RES","I231": #LOCATION = "R63" !CDS_LOCATION = "R63" &SEC = "1" #&CDS_SEC = "1";
"A":   PN = "1"  !CDS_PN = "1";
"B":   PN = "2"  !CDS_PN = "2";
BODY = "Q_RES","I232": #LOCATION = "R82" !CDS_LOCATION = "R82" &SEC = "1" #&CDS_SEC = "1";
"A":   PN = "1"  !CDS_PN = "1";
"B":   PN = "2"  !CDS_PN = "2";
BODY = "Q_RES","I233": #LOCATION = "R64" !CDS_LOCATION = "R64" &SEC = "1" #&CDS_SEC = "1";
"A":   PN = "1"  !CDS_PN = "1";
"B":   PN = "2"  !CDS_PN = "2";
BODY = "Q_RES","I234": #LOCATION = "R823" !CDS_LOCATION = "R823" &SEC = "1" #&CDS_SEC = "1";
"A":   PN = "1"  !CDS_PN = "1";
"B":   PN = "2"  !CDS_PN = "2";
BODY = "Q_RES","I241": #LOCATION = "R828" !CDS_LOCATION = "R828" &SEC = "1" #&CDS_SEC = "1";
"A":   PN = "1"  !CDS_PN = "1";
"B":   PN = "2"  !CDS_PN = "2";
BODY = "Q_RES","I245": #LOCATION = "R81" !CDS_LOCATION = "R81" &SEC = "1" #&CDS_SEC = "1";
"A":   PN = "1"  !CDS_PN = "1";
"B":   PN = "2"  !CDS_PN = "2";
BODY = "Q_RES","I256": #LOCATION = "R169" !CDS_LOCATION = "R169" &SEC = "1" #&CDS_SEC = "1";
"A":   PN = "1"  !CDS_PN = "1";
"B":   PN = "2"  !CDS_PN = "2";
DRAWING = "@scm_lib.scm(sch_1):page12";
BODY = "Q_RES","I2": #LOCATION = "R117" !CDS_LOCATION = "R117" &SEC = "1" #&CDS_SEC = "1";
"A":   PN = "1"  !CDS_PN = "1";
"B":   PN = "2"  !CDS_PN = "2";
BODY = "Q_RES","I3": #LOCATION = "R116" !CDS_LOCATION = "R116" &SEC = "1" #&CDS_SEC = "1";
"A":   PN = "1"  !CDS_PN = "1";
"B":   PN = "2"  !CDS_PN = "2";
BODY = "Q_RES","I4": #LOCATION = "R115" !CDS_LOCATION = "R115" &SEC = "1" #&CDS_SEC = "1";
"A":   PN = "1"  !CDS_PN = "1";
"B":   PN = "2"  !CDS_PN = "2";
BODY = "Q_CAP","I24": #LOCATION = "C21" !CDS_LOCATION = "C21" &SEC = "1" #&CDS_SEC = "1";
"A":   PN = "1"  !CDS_PN = "1";
"B":   PN = "2"  !CDS_PN = "2";
BODY = "Q_CAP","I28": #LOCATION = "C23" !CDS_LOCATION = "C23" &SEC = "1" #&CDS_SEC = "1";
"A":   PN = "1"  !CDS_PN = "1";
"B":   PN = "2"  !CDS_PN = "2";
BODY = "Q_RES","I33": #LOCATION = "R120" !CDS_LOCATION = "R120" &SEC = "1" #&CDS_SEC = "1";
"A":   PN = "1"  !CDS_PN = "1";
"B":   PN = "2"  !CDS_PN = "2";
BODY = "Q_RES","I34": #LOCATION = "R119" !CDS_LOCATION = "R119" &SEC = "1" #&CDS_SEC = "1";
"A":   PN = "1"  !CDS_PN = "1";
"B":   PN = "2"  !CDS_PN = "2";
BODY = "Q_RES","I46": #LOCATION = "R127" !CDS_LOCATION = "R127" &SEC = "1" #&CDS_SEC = "1";
"A":   PN = "1"  !CDS_PN = "1";
"B":   PN = "2"  !CDS_PN = "2";
BODY = "Q_RES","I53": #LOCATION = "R118" !CDS_LOCATION = "R118" &SEC = "1" #&CDS_SEC = "1";
"A":   PN = "1"  !CDS_PN = "1";
"B":   PN = "2"  !CDS_PN = "2";
BODY = "Q_RES","I88": #LOCATION = "R142" !CDS_LOCATION = "R142" &SEC = "1" #&CDS_SEC = "1";
"A":   PN = "1"  !CDS_PN = "1";
"B":   PN = "2"  !CDS_PN = "2";
BODY = "Q_RES","I89": #LOCATION = "R143" !CDS_LOCATION = "R143" &SEC = "1" #&CDS_SEC = "1";
"A":   PN = "1"  !CDS_PN = "1";
"B":   PN = "2"  !CDS_PN = "2";
BODY = "Q_RES","I97": #LOCATION = "R133" !CDS_LOCATION = "R133" &SEC = "1" #&CDS_SEC = "1";
"A":   PN = "1"  !CDS_PN = "1";
"B":   PN = "2"  !CDS_PN = "2";
BODY = "Q_RES","I98": #LOCATION = "R132" !CDS_LOCATION = "R132" &SEC = "1" #&CDS_SEC = "1";
"A":   PN = "1"  !CDS_PN = "1";
"B":   PN = "2"  !CDS_PN = "2";
BODY = "Q_CAP","I152": #LOCATION = "C24" !CDS_LOCATION = "C24" &SEC = "1" #&CDS_SEC = "1";
"A":   PN = "1"  !CDS_PN = "1";
"B":   PN = "2"  !CDS_PN = "2";
BODY = "Q_CAP","I153": #LOCATION = "C25" !CDS_LOCATION = "C25" &SEC = "1" #&CDS_SEC = "1";
"A":   PN = "1"  !CDS_PN = "1";
"B":   PN = "2"  !CDS_PN = "2";
BODY = "Q_RES","I235": #LOCATION = "R146" !CDS_LOCATION = "R146" &SEC = "1" #&CDS_SEC = "1";
"A":   PN = "1"  !CDS_PN = "1";
"B":   PN = "2"  !CDS_PN = "2";
BODY = "Q_RES","I236": #LOCATION = "R147" !CDS_LOCATION = "R147" &SEC = "1" #&CDS_SEC = "1";
"A":   PN = "1"  !CDS_PN = "1";
"B":   PN = "2"  !CDS_PN = "2";
BODY = "Q_RES","I244": #LOCATION = "R236" !CDS_LOCATION = "R236" &SEC = "1" #&CDS_SEC = "1";
"A":   PN = "1"  !CDS_PN = "1";
"B":   PN = "2"  !CDS_PN = "2";
BODY = "Q_RES","I245": #LOCATION = "R162" !CDS_LOCATION = "R162" &SEC = "1" #&CDS_SEC = "1";
"A":   PN = "1"  !CDS_PN = "1";
"B":   PN = "2"  !CDS_PN = "2";
BODY = "Q_RES","I248": #LOCATION = "R153" !CDS_LOCATION = "R153" &SEC = "1" #&CDS_SEC = "1";
"A":   PN = "1"  !CDS_PN = "1";
"B":   PN = "2"  !CDS_PN = "2";
BODY = "Q_RES","I249": #LOCATION = "R152" !CDS_LOCATION = "R152" &SEC = "1" #&CDS_SEC = "1";
"A":   PN = "1"  !CDS_PN = "1";
"B":   PN = "2"  !CDS_PN = "2";
BODY = "Q_RES","I252": #LOCATION = "R423" !CDS_LOCATION = "R423" &SEC = "1" #&CDS_SEC = "1";
"A":   PN = "1"  !CDS_PN = "1";
"B":   PN = "2"  !CDS_PN = "2";
BODY = "Q_RES","I253": #LOCATION = "R424" !CDS_LOCATION = "R424" &SEC = "1" #&CDS_SEC = "1";
"A":   PN = "1"  !CDS_PN = "1";
"B":   PN = "2"  !CDS_PN = "2";
BODY = "Q_RES","I254": #LOCATION = "R425" !CDS_LOCATION = "R425" &SEC = "1" #&CDS_SEC = "1";
"A":   PN = "1"  !CDS_PN = "1";
"B":   PN = "2"  !CDS_PN = "2";
BODY = "Q_RES","I255": #LOCATION = "R426" !CDS_LOCATION = "R426" &SEC = "1" #&CDS_SEC = "1";
"A":   PN = "1"  !CDS_PN = "1";
"B":   PN = "2"  !CDS_PN = "2";
BODY = "Q_RES","I268": #LOCATION = "R168" !CDS_LOCATION = "R168" &SEC = "1" #&CDS_SEC = "1";
"A":   PN = "1"  !CDS_PN = "1";
"B":   PN = "2"  !CDS_PN = "2";
BODY = "Q_RES","I274": #LOCATION = "R567" !CDS_LOCATION = "R567" &SEC = "1" #&CDS_SEC = "1";
"A":   PN = "1"  !CDS_PN = "1";
"B":   PN = "2"  !CDS_PN = "2";
BODY = "Q_RES","I275": #LOCATION = "R570" !CDS_LOCATION = "R570" &SEC = "1" #&CDS_SEC = "1";
"A":   PN = "1"  !CDS_PN = "1";
"B":   PN = "2"  !CDS_PN = "2";
BODY = "Q_RES","I276": #LOCATION = "R93" !CDS_LOCATION = "R93" &SEC = "1" #&CDS_SEC = "1";
"A":   PN = "1"  !CDS_PN = "1";
"B":   PN = "2"  !CDS_PN = "2";
BODY = "Q_RES","I277": #LOCATION = "R71" !CDS_LOCATION = "R71" &SEC = "1" #&CDS_SEC = "1";
"A":   PN = "1"  !CDS_PN = "1";
"B":   PN = "2"  !CDS_PN = "2";
BODY = "Q_RES","I314": #LOCATION = "R394" !CDS_LOCATION = "R394" &SEC = "1" #&CDS_SEC = "1";
"A":   PN = "1"  !CDS_PN = "1";
"B":   PN = "2"  !CDS_PN = "2";
BODY = "Q_RES","I315": #LOCATION = "R165" !CDS_LOCATION = "R165" &SEC = "1" #&CDS_SEC = "1";
"A":   PN = "1"  !CDS_PN = "1";
"B":   PN = "2"  !CDS_PN = "2";
BODY = "Q_RES","I316": #LOCATION = "R589" !CDS_LOCATION = "R589" &SEC = "1" #&CDS_SEC = "1";
"A":   PN = "1"  !CDS_PN = "1";
"B":   PN = "2"  !CDS_PN = "2";
BODY = "Q_RES","I317": #LOCATION = "R590" !CDS_LOCATION = "R590" &SEC = "1" #&CDS_SEC = "1";
"A":   PN = "1"  !CDS_PN = "1";
"B":   PN = "2"  !CDS_PN = "2";
BODY = "Q_RES","I318": #LOCATION = "R582" !CDS_LOCATION = "R582" &SEC = "1" #&CDS_SEC = "1";
"A":   PN = "1"  !CDS_PN = "1";
"B":   PN = "2"  !CDS_PN = "2";
BODY = "Q_RES","I319": #LOCATION = "R583" !CDS_LOCATION = "R583" &SEC = "1" #&CDS_SEC = "1";
"A":   PN = "1"  !CDS_PN = "1";
"B":   PN = "2"  !CDS_PN = "2";
BODY = "Q_RES","I320": #LOCATION = "R584" !CDS_LOCATION = "R584" &SEC = "1" #&CDS_SEC = "1";
"A":   PN = "1"  !CDS_PN = "1";
"B":   PN = "2"  !CDS_PN = "2";
BODY = "Q_RES","I321": #LOCATION = "R580" !CDS_LOCATION = "R580" &SEC = "1" #&CDS_SEC = "1";
"A":   PN = "1"  !CDS_PN = "1";
"B":   PN = "2"  !CDS_PN = "2";
BODY = "Q_RES","I350": #LOCATION = "R62" !CDS_LOCATION = "R62" &SEC = "1" #&CDS_SEC = "1";
"A":   PN = "1"  !CDS_PN = "1";
"B":   PN = "2"  !CDS_PN = "2";
BODY = "Q_RES","I353": #LOCATION = "R705" !CDS_LOCATION = "R705" &SEC = "1" #&CDS_SEC = "1";
"A":   PN = "1"  !CDS_PN = "1";
"B":   PN = "2"  !CDS_PN = "2";
BODY = "Q_RES","I354": #LOCATION = "R706" !CDS_LOCATION = "R706" &SEC = "1" #&CDS_SEC = "1";
"A":   PN = "1"  !CDS_PN = "1";
"B":   PN = "2"  !CDS_PN = "2";
BODY = "Q_RES","I379": #LOCATION = "R148" !CDS_LOCATION = "R148" &SEC = "1" #&CDS_SEC = "1";
"A":   PN = "1"  !CDS_PN = "1";
"B":   PN = "2"  !CDS_PN = "2";
BODY = "Q_RES","I380": #LOCATION = "R150" !CDS_LOCATION = "R150" &SEC = "1" #&CDS_SEC = "1";
"A":   PN = "1"  !CDS_PN = "1";
"B":   PN = "2"  !CDS_PN = "2";
BODY = "Q_RES","I381": #LOCATION = "R151" !CDS_LOCATION = "R151" &SEC = "1" #&CDS_SEC = "1";
"A":   PN = "1"  !CDS_PN = "1";
"B":   PN = "2"  !CDS_PN = "2";
BODY = "Q_RES","I382": #LOCATION = "R433" !CDS_LOCATION = "R433" &SEC = "1" #&CDS_SEC = "1";
"A":   PN = "1"  !CDS_PN = "1";
"B":   PN = "2"  !CDS_PN = "2";
BODY = "Q_RES","I385": #LOCATION = "R137" !CDS_LOCATION = "R137" &SEC = "1" #&CDS_SEC = "1";
"A":   PN = "1"  !CDS_PN = "1";
"B":   PN = "2"  !CDS_PN = "2";
BODY = "Q_RES","I386": #LOCATION = "R144" !CDS_LOCATION = "R144" &SEC = "1" #&CDS_SEC = "1";
"A":   PN = "1"  !CDS_PN = "1";
"B":   PN = "2"  !CDS_PN = "2";
BODY = "Q_RES","I390": #LOCATION = "R820" !CDS_LOCATION = "R820" #SEC = "1" !CDS_SEC = "1";
"A":   PN = "1"  !CDS_PN = "1";
"B":   PN = "2"  !CDS_PN = "2";
BODY = "Q_RES","I391": #LOCATION = "R819" !CDS_LOCATION = "R819" #SEC = "1" !CDS_SEC = "1";
"A":   PN = "1"  !CDS_PN = "1";
"B":   PN = "2"  !CDS_PN = "2";
BODY = "Q_RES","I392": #LOCATION = "R818" !CDS_LOCATION = "R818" #SEC = "1" !CDS_SEC = "1";
"A":   PN = "1"  !CDS_PN = "1";
"B":   PN = "2"  !CDS_PN = "2";
BODY = "Q_RES","I393": #LOCATION = "R817" !CDS_LOCATION = "R817" #SEC = "1" !CDS_SEC = "1";
"A":   PN = "1"  !CDS_PN = "1";
"B":   PN = "2"  !CDS_PN = "2";
BODY = "Q_CAP","I428": LOCATION = "C272" #&CDS_LOCATION = "C272" &SEC = "1" #&CDS_SEC = "1";
"A":   PN = "1"  !CDS_PN = "1";
"B":   PN = "2"  !CDS_PN = "2";
BODY = "Q_CAP","I429": LOCATION = "C271" #&CDS_LOCATION = "C271" &SEC = "1" #&CDS_SEC = "1";
"A":   PN = "1"  !CDS_PN = "1";
"B":   PN = "2"  !CDS_PN = "2";
BODY = "AST2600A3GP","I436": #LOCATION = "U5" !CDS_LOCATION = "U5" &SEC = "1" #&CDS_SEC = "1";
"DPAUXN":   PN = "AB3"  !CDS_PN = "AB3";
"DPAUXP":   PN = "AC3"  !CDS_PN = "AC3";
"DPHPD":   PN = "C7"  !CDS_PN = "C7";
"DPTXN0":   PN = "AB1"  !CDS_PN = "AB1";
"DPTXN1":   PN = "AA2"  !CDS_PN = "AA2";
"DPTXP0":   PN = "AC1"  !CDS_PN = "AC1";
"DPTXP1":   PN = "AB2"  !CDS_PN = "AB2";
"GPIOA0||SCL11||MDC3":   PN = "M24"  !CDS_PN = "M24";
"GPIOA1||SDA11||MDIO3":   PN = "M25"  !CDS_PN = "M25";
"GPIOA2||SCL12||MDC4":   PN = "L26"  !CDS_PN = "L26";
"GPIOA3||SDA12||MDIO4":   PN = "K24"  !CDS_PN = "K24";
"GPIOA4||MAC1LINK||SCL13||SGPM2CK||SGPS2CK":   PN = "K26"  !CDS_PN = "K26";
"GPIOA5||MAC2LINK||SDA13||SGPM2LD||SGPS2LD":   PN = "L24"  !CDS_PN = "L24";
"GPIOA6||MAC3LINK||SCL14||SGPM2O||SGPS2I0":   PN = "L23"  !CDS_PN = "L23";
"GPIOA7||MAC4LINK||SDA14||SGPM2I||SGPS2I1":   PN = "K25"  !CDS_PN = "K25";
"GPIOF0||SD1CLK||PWM8":   PN = "D22"  !CDS_PN = "D22";
"GPIOF1||SD1CMD||PWM9":   PN = "E22"  !CDS_PN = "E22";
"GPIOF2||SD1DAT0||PWM10":   PN = "D23"  !CDS_PN = "D23";
"GPIOF3||SD1DAT1||PWM11":   PN = "C23"  !CDS_PN = "C23";
"GPIOF4||SD1DAT2||PWM12":   PN = "C22"  !CDS_PN = "C22";
"GPIOF5||SD1DAT3||PWM13":   PN = "A25"  !CDS_PN = "A25";
"GPIOF6||SD1CD#||PWM14":   PN = "A24"  !CDS_PN = "A24";
"GPIOF7||SD1WP#||PWM15":   PN = "A23"  !CDS_PN = "A23";
"GPIOG0||TXD6||SD2CLK||SALT9":   PN = "E21"  !CDS_PN = "E21";
"GPIOG1||RXD6||SD2CMD||SALT10":   PN = "B22"  !CDS_PN = "B22";
"GPIOG2||TXD7||SD2DAT0||SALT11":   PN = "C21"  !CDS_PN = "C21";
"GPIOG3||RXD7||SD2DAT1||SALT12":   PN = "A22"  !CDS_PN = "A22";
"GPIOG4||TXD8||SD2DAT2||SALT13":   PN = "A21"  !CDS_PN = "A21";
"GPIOG5||RXD8||SD2DAT3||SALT14":   PN = "E20"  !CDS_PN = "E20";
"GPIOG6||TXD9||SD2CD#||SALT15":   PN = "D21"  !CDS_PN = "D21";
"GPIOG7||RXD9||SD2WP#||SALT16":   PN = "B21"  !CDS_PN = "B21";
"GPIOH0||SGPM1CK":   PN = "A18"  !CDS_PN = "A18";
"GPIOH1||SGPM1LD":   PN = "B18"  !CDS_PN = "B18";
"GPIOH2||SGPM1O":   PN = "C18"  !CDS_PN = "C18";
"GPIOH3||SGPM1I":   PN = "A17"  !CDS_PN = "A17";
"GPIOH4||SGPS1CK||SCL15":   PN = "D18"  !CDS_PN = "D18";
"GPIOH5||SGPS1LD||SDA15":   PN = "B17"  !CDS_PN = "B17";
"GPIOH6||SGPS1I0||SCL16":   PN = "C17"  !CDS_PN = "C17";
"GPIOH7||SGPS1I1||SDA16":   PN = "E18"  !CDS_PN = "E18";
"GPIOJ0||HVI3C3SCL||SCL1":   PN = "B20"  !CDS_PN = "B20";
"GPIOJ1||HVI3C3SDA||SDA1":   PN = "A20"  !CDS_PN = "A20";
"GPIOJ2||HVI3C4SCL||SCL2":   PN = "E19"  !CDS_PN = "E19";
"GPIOJ3||HVI3C4SDA||SDA2":   PN = "D20"  !CDS_PN = "D20";
"GPIOJ4||HVI3C5SCL||SCL3":   PN = "C19"  !CDS_PN = "C19";
"GPIOJ5||HVI3C5SDA||SDA3":   PN = "A19"  !CDS_PN = "A19";
"GPIOJ6||HVI3C6SCL||SCL4":   PN = "C20"  !CDS_PN = "C20";
"GPIOJ7||HVI3C6SDA||SDA4":   PN = "D19"  !CDS_PN = "D19";
"GPIOK0||SCL5":   PN = "A11"  !CDS_PN = "A11";
"GPIOK1||SDA5":   PN = "C11"  !CDS_PN = "C11";
"GPIOK2||SCL6":   PN = "D12"  !CDS_PN = "D12";
"GPIOK3||SDA6":   PN = "E13"  !CDS_PN = "E13";
"GPIOK4||SCL7":   PN = "D11"  !CDS_PN = "D11";
"GPIOK5||SDA7":   PN = "E11"  !CDS_PN = "E11";
"GPIOK6||SCL8":   PN = "F13"  !CDS_PN = "F13";
"GPIOK7||SDA8":   PN = "E12"  !CDS_PN = "E12";
"GPIOL0||SCL9":   PN = "D15"  !CDS_PN = "D15";
"GPIOL1||SDA9":   PN = "A14"  !CDS_PN = "A14";
"GPIOL2||SCL10":   PN = "E15"  !CDS_PN = "E15";
"GPIOL3||SDA10":   PN = "A13"  !CDS_PN = "A13";
"GPIOS2||PEWAKE#":   PN = "T26"  !CDS_PN = "T26";
"GPIOS3||OSCCLK":   PN = "R24"  !CDS_PN = "R24";
"GPIOW0||LAD0||ESPID0":   PN = "AB7"  !CDS_PN = "AB7";
"GPIOW1||LAD1||ESPID1":   PN = "AB8"  !CDS_PN = "AB8";
"GPIOW2||LAD2||ESPID2":   PN = "AC8"  !CDS_PN = "AC8";
"GPIOW3||LAD3||ESPID3":   PN = "AC7"  !CDS_PN = "AC7";
"GPIOW4||LCLK||ESPICK":   PN = "AE7"  !CDS_PN = "AE7";
"GPIOW5||LFRAME#||ESPICS#":   PN = "AF7"  !CDS_PN = "AF7";
"GPIOW6||LSIRQ#||ESPIALT#":   PN = "AD7"  !CDS_PN = "AD7";
"GPIOW7||LPCRST#||ESPIRST#":   PN = "AD8"  !CDS_PN = "AD8";
"MA0":   PN = "F3"  !CDS_PN = "F3";
"MA1":   PN = "K5"  !CDS_PN = "K5";
"MA2":   PN = "F1"  !CDS_PN = "F1";
"MA3":   PN = "H3"  !CDS_PN = "H3";
"MA4":   PN = "J3"  !CDS_PN = "J3";
"MA5":   PN = "L1"  !CDS_PN = "L1";
"MA6":   PN = "M5"  !CDS_PN = "M5";
"MA7":   PN = "M2"  !CDS_PN = "M2";
"MA8":   PN = "M1"  !CDS_PN = "M1";
"MA9":   PN = "N1"  !CDS_PN = "N1";
"MA10":   PN = "F2"  !CDS_PN = "F2";
"MA11":   PN = "G1"  !CDS_PN = "G1";
"MA12":   PN = "L4"  !CDS_PN = "L4";
"MA13":   PN = "K3"  !CDS_PN = "K3";
"MA14||MACT#":   PN = "H1"  !CDS_PN = "H1";
"MA15||MBG1":   PN = "M3"  !CDS_PN = "M3";
"MALERT#":   PN = "N4"  !CDS_PN = "N4";
"MBA0":   PN = "G4"  !CDS_PN = "G4";
"MBA1":   PN = "H5"  !CDS_PN = "H5";
"MBA2||MBG0":   PN = "G3"  !CDS_PN = "G3";
"MCAS#":   PN = "J4"  !CDS_PN = "J4";
"MCK":   PN = "K2"  !CDS_PN = "K2";
"MCK#":   PN = "K1"  !CDS_PN = "K1";
"MCKE":   PN = "L5"  !CDS_PN = "L5";
"MCS#":   PN = "H2"  !CDS_PN = "H2";
"MDM0":   PN = "N3"  !CDS_PN = "N3";
"MDM1":   PN = "R5"  !CDS_PN = "R5";
"MDQ0":   PN = "T3"  !CDS_PN = "T3";
"MDQ1":   PN = "R4"  !CDS_PN = "R4";
"MDQ2":   PN = "U1"  !CDS_PN = "U1";
"MDQ3":   PN = "R3"  !CDS_PN = "R3";
"MDQ4":   PN = "R1"  !CDS_PN = "R1";
"MDQ5":   PN = "P1"  !CDS_PN = "P1";
"MDQ6":   PN = "P2"  !CDS_PN = "P2";
"MDQ7":   PN = "P3"  !CDS_PN = "P3";
"MDQ8":   PN = "W2"  !CDS_PN = "W2";
"MDQ9":   PN = "V3"  !CDS_PN = "V3";
"MDQ10":   PN = "W1"  !CDS_PN = "W1";
"MDQ11":   PN = "W3"  !CDS_PN = "W3";
"MDQ12":   PN = "W4"  !CDS_PN = "W4";
"MDQ13":   PN = "U4"  !CDS_PN = "U4";
"MDQ14":   PN = "V4"  !CDS_PN = "V4";
"MDQ15":   PN = "U3"  !CDS_PN = "U3";
"MDQS0":   PN = "T2"  !CDS_PN = "T2";
"MDQS0#":   PN = "T1"  !CDS_PN = "T1";
"MDQS1":   PN = "V2"  !CDS_PN = "V2";
"MDQS1#":   PN = "V1"  !CDS_PN = "V1";
"MIOZ":   PN = "P5"  !CDS_PN = "P5";
"MODT":   PN = "J1"  !CDS_PN = "J1";
"MRAS#":   PN = "J5"  !CDS_PN = "J5";
"MRESET#":   PN = "L3"  !CDS_PN = "L3";
"MVREF_T5":   PN = "T5"  !CDS_PN = "T5";
"MVREF_U5":   PN = "U5"  !CDS_PN = "U5";
"MWE#":   PN = "G5"  !CDS_PN = "G5";
"PEREFCLKN":   PN = "AD6"  !CDS_PN = "AD6";
"PEREFCLKP":   PN = "AD5"  !CDS_PN = "AD5";
"PERST#":   PN = "A7"  !CDS_PN = "A7";
"PERXN":   PN = "AF6"  !CDS_PN = "AF6";
"PERXP":   PN = "AF5"  !CDS_PN = "AF5";
"PETXN":   PN = "AE5"  !CDS_PN = "AE5";
"PETXP":   PN = "AE4"  !CDS_PN = "AE4";
"RCREFCLKN":   PN = "AE2"  !CDS_PN = "AE2";
"RCREFCLKP":   PN = "AE1"  !CDS_PN = "AE1";
"RCRXN":   PN = "AD3"  !CDS_PN = "AD3";
"RCRXP":   PN = "AD2"  !CDS_PN = "AD2";
"RCTXN":   PN = "AF3"  !CDS_PN = "AF3";
"RCTXP":   PN = "AF2"  !CDS_PN = "AF2";
BODY = "Q_RES","I441": LOCATION = "R310" #&CDS_LOCATION = "R310" &SEC = "1" #&CDS_SEC = "1";
"A":   PN = "1"  !CDS_PN = "1";
"B":   PN = "2"  !CDS_PN = "2";
BODY = "Q_RES","I442": #LOCATION = "R128" !CDS_LOCATION = "R128" &SEC = "1" #&CDS_SEC = "1";
"A":   PN = "1"  !CDS_PN = "1";
"B":   PN = "2"  !CDS_PN = "2";
BODY = "Q_RES","I443": #LOCATION = "R131" !CDS_LOCATION = "R131" &SEC = "1" #&CDS_SEC = "1";
"A":   PN = "1"  !CDS_PN = "1";
"B":   PN = "2"  !CDS_PN = "2";
BODY = "Q_RES","I444": #LOCATION = "R130" !CDS_LOCATION = "R130" &SEC = "1" #&CDS_SEC = "1";
"A":   PN = "1"  !CDS_PN = "1";
"B":   PN = "2"  !CDS_PN = "2";
BODY = "Q_RES","I445": #LOCATION = "R129" !CDS_LOCATION = "R129" &SEC = "1" #&CDS_SEC = "1";
"A":   PN = "1"  !CDS_PN = "1";
"B":   PN = "2"  !CDS_PN = "2";
BODY = "Q_RES","I447": LOCATION = "R311" #&CDS_LOCATION = "R311" &SEC = "1" #&CDS_SEC = "1";
"A":   PN = "1"  !CDS_PN = "1";
"B":   PN = "2"  !CDS_PN = "2";
BODY = "Q_CAP","I448": #LOCATION = "C22" !CDS_LOCATION = "C22" &SEC = "1" #&CDS_SEC = "1";
"A":   PN = "1"  !CDS_PN = "1";
"B":   PN = "2"  !CDS_PN = "2";
BODY = "Q_RES","I454": LOCATION = "R400" #&CDS_LOCATION = "R400" &SEC = "1" #&CDS_SEC = "1";
"A":   PN = "1"  !CDS_PN = "1";
"B":   PN = "2"  !CDS_PN = "2";
BODY = "Q_RES","I456": LOCATION = "R312" #&CDS_LOCATION = "R312" &SEC = "1" #&CDS_SEC = "1";
"A":   PN = "1"  !CDS_PN = "1";
"B":   PN = "2"  !CDS_PN = "2";
BODY = "Q_RES","I458": LOCATION = "R880" #&CDS_LOCATION = "R880" &SEC = "1" #&CDS_SEC = "1";
"A":   PN = "1"  !CDS_PN = "1";
"B":   PN = "2"  !CDS_PN = "2";
BODY = "Q_RES","I473": #LOCATION = "R761" !CDS_LOCATION = "R761" &SEC = "1" #&CDS_SEC = "1";
"A":   PN = "1"  !CDS_PN = "1";
"B":   PN = "2"  !CDS_PN = "2";
BODY = "Q_RES","I474": #LOCATION = "R762" !CDS_LOCATION = "R762" &SEC = "1" #&CDS_SEC = "1";
"A":   PN = "1"  !CDS_PN = "1";
"B":   PN = "2"  !CDS_PN = "2";
BODY = "Q_RES","I508": LOCATION = "R387" #&CDS_LOCATION = "R387" &SEC = "1" #&CDS_SEC = "1";
"A":   PN = "1"  !CDS_PN = "1";
"B":   PN = "2"  !CDS_PN = "2";
BODY = "Q_RES","I510": #LOCATION = "R879" !CDS_LOCATION = "R879" &SEC = "1" #&CDS_SEC = "1";
"A":   PN = "1"  !CDS_PN = "1";
"B":   PN = "2"  !CDS_PN = "2";
BODY = "Q_RES","I512": #LOCATION = "R139" !CDS_LOCATION = "R139" &SEC = "1" #&CDS_SEC = "1";
"A":   PN = "1"  !CDS_PN = "1";
"B":   PN = "2"  !CDS_PN = "2";
BODY = "Q_RES","I513": #LOCATION = "R138" !CDS_LOCATION = "R138" &SEC = "1" #&CDS_SEC = "1";
"A":   PN = "1"  !CDS_PN = "1";
"B":   PN = "2"  !CDS_PN = "2";
DRAWING = "@scm_lib.scm(sch_1):page13";
BODY = "Q_RES","I3": #LOCATION = "R154" !CDS_LOCATION = "R154" &SEC = "1" #&CDS_SEC = "1";
"A":   PN = "1"  !CDS_PN = "1";
"B":   PN = "2"  !CDS_PN = "2";
BODY = "Q_RES","I4": #LOCATION = "R156" !CDS_LOCATION = "R156" &SEC = "1" #&CDS_SEC = "1";
"A":   PN = "1"  !CDS_PN = "1";
"B":   PN = "2"  !CDS_PN = "2";
BODY = "Q_RES","I5": #LOCATION = "R155" !CDS_LOCATION = "R155" &SEC = "1" #&CDS_SEC = "1";
"A":   PN = "1"  !CDS_PN = "1";
"B":   PN = "2"  !CDS_PN = "2";
BODY = "Q_RES","I16": #LOCATION = "R158" !CDS_LOCATION = "R158" &SEC = "1" #&CDS_SEC = "1";
"A":   PN = "1"  !CDS_PN = "1";
"B":   PN = "2"  !CDS_PN = "2";
BODY = "Q_RES","I17": #LOCATION = "R159" !CDS_LOCATION = "R159" &SEC = "1" #&CDS_SEC = "1";
"A":   PN = "1"  !CDS_PN = "1";
"B":   PN = "2"  !CDS_PN = "2";
BODY = "Q_RES","I18": #LOCATION = "R157" !CDS_LOCATION = "R157" &SEC = "1" #&CDS_SEC = "1";
"A":   PN = "1"  !CDS_PN = "1";
"B":   PN = "2"  !CDS_PN = "2";
BODY = "Q_CAP","I29": #LOCATION = "C30" !CDS_LOCATION = "C30" &SEC = "1" #&CDS_SEC = "1";
"A":   PN = "1"  !CDS_PN = "1";
"B":   PN = "2"  !CDS_PN = "2";
BODY = "Q_CAP","I30": #LOCATION = "C31" !CDS_LOCATION = "C31" &SEC = "1" #&CDS_SEC = "1";
"A":   PN = "1"  !CDS_PN = "1";
"B":   PN = "2"  !CDS_PN = "2";
BODY = "Q_CAP","I31": #LOCATION = "C32" !CDS_LOCATION = "C32" &SEC = "1" #&CDS_SEC = "1";
"A":   PN = "1"  !CDS_PN = "1";
"B":   PN = "2"  !CDS_PN = "2";
BODY = "Q_CAP","I32": #LOCATION = "C33" !CDS_LOCATION = "C33" &SEC = "1" #&CDS_SEC = "1";
"A":   PN = "1"  !CDS_PN = "1";
"B":   PN = "2"  !CDS_PN = "2";
BODY = "Q_RES","I33": #LOCATION = "R167" !CDS_LOCATION = "R167" &SEC = "1" #&CDS_SEC = "1";
"A":   PN = "1"  !CDS_PN = "1";
"B":   PN = "2"  !CDS_PN = "2";
BODY = "Q_LED","I46": #LOCATION = "D8" !CDS_LOCATION = "D8" &SEC = "1" #&CDS_SEC = "1";
"A":   PN = "A"  !CDS_PN = "A";
"C":   PN = "C"  !CDS_PN = "C";
BODY = "Q_RES","I50": #LOCATION = "R166" !CDS_LOCATION = "R166" &SEC = "1" #&CDS_SEC = "1";
"A":   PN = "1"  !CDS_PN = "1";
"B":   PN = "2"  !CDS_PN = "2";
BODY = "Q_RES","I67": #LOCATION = "R170" !CDS_LOCATION = "R170" &SEC = "1" #&CDS_SEC = "1";
"A":   PN = "1"  !CDS_PN = "1";
"B":   PN = "2"  !CDS_PN = "2";
BODY = "Q_RES","I87": #LOCATION = "R177" !CDS_LOCATION = "R177" #SEC = "1" !CDS_SEC = "1";
"A":   PN = "1"  !CDS_PN = "1";
"B":   PN = "2"  !CDS_PN = "2";
BODY = "Q_RES","I94": #LOCATION = "R178" !CDS_LOCATION = "R178" &SEC = "1" #&CDS_SEC = "1";
"A":   PN = "1"  !CDS_PN = "1";
"B":   PN = "2"  !CDS_PN = "2";
BODY = "Q_RES","I95": #LOCATION = "R179" !CDS_LOCATION = "R179" &SEC = "1" #&CDS_SEC = "1";
"A":   PN = "1"  !CDS_PN = "1";
"B":   PN = "2"  !CDS_PN = "2";
BODY = "Q_RES","I96": #LOCATION = "R180" !CDS_LOCATION = "R180" &SEC = "1" #&CDS_SEC = "1";
"A":   PN = "1"  !CDS_PN = "1";
"B":   PN = "2"  !CDS_PN = "2";
BODY = "Q_RES","I133": #LOCATION = "R37" !CDS_LOCATION = "R37" &SEC = "1" #&CDS_SEC = "1";
"A":   PN = "1"  !CDS_PN = "1";
"B":   PN = "2"  !CDS_PN = "2";
BODY = "Q_RES","I156": #LOCATION = "R237" !CDS_LOCATION = "R237" &SEC = "1" #&CDS_SEC = "1";
"A":   PN = "1"  !CDS_PN = "1";
"B":   PN = "2"  !CDS_PN = "2";
BODY = "Q_RES","I159": #LOCATION = "R160" !CDS_LOCATION = "R160" &SEC = "1" #&CDS_SEC = "1";
"A":   PN = "1"  !CDS_PN = "1";
"B":   PN = "2"  !CDS_PN = "2";
BODY = "Q_RES","I184": #LOCATION = "R238" !CDS_LOCATION = "R238" &SEC = "1" #&CDS_SEC = "1";
"A":   PN = "1"  !CDS_PN = "1";
"B":   PN = "2"  !CDS_PN = "2";
BODY = "Q_RES","I185": #LOCATION = "R239" !CDS_LOCATION = "R239" &SEC = "1" #&CDS_SEC = "1";
"A":   PN = "1"  !CDS_PN = "1";
"B":   PN = "2"  !CDS_PN = "2";
BODY = "Q_RES","I186": #LOCATION = "R241" !CDS_LOCATION = "R241" &SEC = "1" #&CDS_SEC = "1";
"A":   PN = "1"  !CDS_PN = "1";
"B":   PN = "2"  !CDS_PN = "2";
BODY = "Q_RES","I187": #LOCATION = "R240" !CDS_LOCATION = "R240" &SEC = "1" #&CDS_SEC = "1";
"A":   PN = "1"  !CDS_PN = "1";
"B":   PN = "2"  !CDS_PN = "2";
BODY = "Q_RES","I188": #LOCATION = "R683" !CDS_LOCATION = "R683" &SEC = "1" #&CDS_SEC = "1";
"A":   PN = "1"  !CDS_PN = "1";
"B":   PN = "2"  !CDS_PN = "2";
BODY = "Q_RES","I198": #LOCATION = "R427" !CDS_LOCATION = "R427" &SEC = "1" #&CDS_SEC = "1";
"A":   PN = "1"  !CDS_PN = "1";
"B":   PN = "2"  !CDS_PN = "2";
BODY = "Q_RES","I200": #LOCATION = "R38" !CDS_LOCATION = "R38" &SEC = "1" #&CDS_SEC = "1";
"A":   PN = "1"  !CDS_PN = "1";
"B":   PN = "2"  !CDS_PN = "2";
BODY = "Q_RES","I204": #LOCATION = "R61" !CDS_LOCATION = "R61" &SEC = "1" #&CDS_SEC = "1";
"A":   PN = "1"  !CDS_PN = "1";
"B":   PN = "2"  !CDS_PN = "2";
BODY = "Q_RES","I208": #LOCATION = "R759" !CDS_LOCATION = "R759" &SEC = "1" #&CDS_SEC = "1";
"A":   PN = "1"  !CDS_PN = "1";
"B":   PN = "2"  !CDS_PN = "2";
BODY = "Q_RES","I213": #LOCATION = "R774" !CDS_LOCATION = "R774" &SEC = "1" #&CDS_SEC = "1";
"A":   PN = "1"  !CDS_PN = "1";
"B":   PN = "2"  !CDS_PN = "2";
BODY = "Q_RES","I215": #LOCATION = "R799" !CDS_LOCATION = "R799" &SEC = "1" #&CDS_SEC = "1";
"A":   PN = "1"  !CDS_PN = "1";
"B":   PN = "2"  !CDS_PN = "2";
BODY = "Q_RES","I217": #LOCATION = "R801" !CDS_LOCATION = "R801" &SEC = "1" #&CDS_SEC = "1";
"A":   PN = "1"  !CDS_PN = "1";
"B":   PN = "2"  !CDS_PN = "2";
BODY = "Q_RES","I218": #LOCATION = "R802" !CDS_LOCATION = "R802" &SEC = "1" #&CDS_SEC = "1";
"A":   PN = "1"  !CDS_PN = "1";
"B":   PN = "2"  !CDS_PN = "2";
BODY = "Q_RES","I220": #LOCATION = "R821" !CDS_LOCATION = "R821" &SEC = "1" #&CDS_SEC = "1";
"A":   PN = "1"  !CDS_PN = "1";
"B":   PN = "2"  !CDS_PN = "2";
BODY = "Q_RES","I223": #LOCATION = "R824" !CDS_LOCATION = "R824" &SEC = "1" #&CDS_SEC = "1";
"A":   PN = "1"  !CDS_PN = "1";
"B":   PN = "2"  !CDS_PN = "2";
BODY = "Q_RES","I225": #LOCATION = "R836" !CDS_LOCATION = "R836" &SEC = "1" #&CDS_SEC = "1";
"A":   PN = "1"  !CDS_PN = "1";
"B":   PN = "2"  !CDS_PN = "2";
BODY = "Q_RES","I227": #LOCATION = "R439" !CDS_LOCATION = "R439" &SEC = "1" #&CDS_SEC = "1";
"A":   PN = "1"  !CDS_PN = "1";
"B":   PN = "2"  !CDS_PN = "2";
BODY = "Q_RES","I239": #LOCATION = "R678" !CDS_LOCATION = "R678" &SEC = "1" #&CDS_SEC = "1";
"A":   PN = "1"  !CDS_PN = "1";
"B":   PN = "2"  !CDS_PN = "2";
BODY = "Q_RES","I245": #LOCATION = "R681" !CDS_LOCATION = "R681" &SEC = "1" #&CDS_SEC = "1";
"A":   PN = "1"  !CDS_PN = "1";
"B":   PN = "2"  !CDS_PN = "2";
BODY = "Q_RES","I246": #LOCATION = "R682" !CDS_LOCATION = "R682" &SEC = "1" #&CDS_SEC = "1";
"A":   PN = "1"  !CDS_PN = "1";
"B":   PN = "2"  !CDS_PN = "2";
BODY = "Q_RES","I247": #LOCATION = "R679" !CDS_LOCATION = "R679" &SEC = "1" #&CDS_SEC = "1";
"A":   PN = "1"  !CDS_PN = "1";
"B":   PN = "2"  !CDS_PN = "2";
BODY = "Q_RES","I248": #LOCATION = "R680" !CDS_LOCATION = "R680" &SEC = "1" #&CDS_SEC = "1";
"A":   PN = "1"  !CDS_PN = "1";
"B":   PN = "2"  !CDS_PN = "2";
BODY = "Q_RES","I266": #LOCATION = "R111" !CDS_LOCATION = "R111" #SEC = "1" !CDS_SEC = "1";
"A":   PN = "1"  !CDS_PN = "1";
"B":   PN = "2"  !CDS_PN = "2";
BODY = "Q_RES","I278": #LOCATION = "R55" !CDS_LOCATION = "R55" #SEC = "1" !CDS_SEC = "1";
"A":   PN = "1"  !CDS_PN = "1";
"B":   PN = "2"  !CDS_PN = "2";
BODY = "Q_RES","I279": #LOCATION = "R56" !CDS_LOCATION = "R56" #SEC = "1" !CDS_SEC = "1";
"A":   PN = "1"  !CDS_PN = "1";
"B":   PN = "2"  !CDS_PN = "2";
BODY = "Q_RES","I286": #LOCATION = "R96" !CDS_LOCATION = "R96" #SEC = "1" !CDS_SEC = "1";
"A":   PN = "1"  !CDS_PN = "1";
"B":   PN = "2"  !CDS_PN = "2";
BODY = "Q_RES","I295": #LOCATION = "R840" !CDS_LOCATION = "R840" &SEC = "1" #&CDS_SEC = "1";
"A":   PN = "1"  !CDS_PN = "1";
"B":   PN = "2"  !CDS_PN = "2";
BODY = "Q_RES","I299": #LOCATION = "R446" !CDS_LOCATION = "R446" #SEC = "1" !CDS_SEC = "1";
"A":   PN = "1"  !CDS_PN = "1";
"B":   PN = "2"  !CDS_PN = "2";
BODY = "Q_RES","I300": #LOCATION = "R443" !CDS_LOCATION = "R443" &SEC = "1" #&CDS_SEC = "1";
"A":   PN = "1"  !CDS_PN = "1";
"B":   PN = "2"  !CDS_PN = "2";
BODY = "Q_RES","I301": #LOCATION = "R442" !CDS_LOCATION = "R442" &SEC = "1" #&CDS_SEC = "1";
"A":   PN = "1"  !CDS_PN = "1";
"B":   PN = "2"  !CDS_PN = "2";
BODY = "Q_RES","I306": #LOCATION = "R444" !CDS_LOCATION = "R444" &SEC = "1" #&CDS_SEC = "1";
"A":   PN = "1"  !CDS_PN = "1";
"B":   PN = "2"  !CDS_PN = "2";
BODY = "Q_RES","I312": #LOCATION = "R460" !CDS_LOCATION = "R460" &SEC = "1" #&CDS_SEC = "1";
"A":   PN = "1"  !CDS_PN = "1";
"B":   PN = "2"  !CDS_PN = "2";
BODY = "Q_RES","I319": #LOCATION = "R469" !CDS_LOCATION = "R469" &SEC = "1" #&CDS_SEC = "1";
"A":   PN = "1"  !CDS_PN = "1";
"B":   PN = "2"  !CDS_PN = "2";
BODY = "Q_RES","I335": #LOCATION = "R494" !CDS_LOCATION = "R494" #SEC = "1" !CDS_SEC = "1";
"A":   PN = "1"  !CDS_PN = "1";
"B":   PN = "2"  !CDS_PN = "2";
BODY = "Q_RES","I337": #LOCATION = "R637" !CDS_LOCATION = "R637" &SEC = "1" #&CDS_SEC = "1";
"A":   PN = "1"  !CDS_PN = "1";
"B":   PN = "2"  !CDS_PN = "2";
BODY = "Q_RES","I339": #LOCATION = "R452" !CDS_LOCATION = "R452" #SEC = "1" !CDS_SEC = "1";
"A":   PN = "1"  !CDS_PN = "1";
"B":   PN = "2"  !CDS_PN = "2";
BODY = "Q_RES","I340": #LOCATION = "R273" !CDS_LOCATION = "R273" #SEC = "1" !CDS_SEC = "1";
"A":   PN = "1"  !CDS_PN = "1";
"B":   PN = "2"  !CDS_PN = "2";
BODY = "Q_RES","I344": #LOCATION = "R643" !CDS_LOCATION = "R643" &SEC = "1" #&CDS_SEC = "1";
"A":   PN = "1"  !CDS_PN = "1";
"B":   PN = "2"  !CDS_PN = "2";
BODY = "Q_RES","I349": #LOCATION = "R407" !CDS_LOCATION = "R407" #SEC = "1" !CDS_SEC = "1";
"A":   PN = "1"  !CDS_PN = "1";
"B":   PN = "2"  !CDS_PN = "2";
BODY = "Q_RES","I350": #LOCATION = "R722" !CDS_LOCATION = "R722" &SEC = "1" #&CDS_SEC = "1";
"A":   PN = "1"  !CDS_PN = "1";
"B":   PN = "2"  !CDS_PN = "2";
BODY = "Q_RES","I351": #LOCATION = "R826" !CDS_LOCATION = "R826" &SEC = "1" #&CDS_SEC = "1";
"A":   PN = "1"  !CDS_PN = "1";
"B":   PN = "2"  !CDS_PN = "2";
BODY = "Q_RES","I353": #LOCATION = "R816" !CDS_LOCATION = "R816" &SEC = "1" #&CDS_SEC = "1";
"A":   PN = "1"  !CDS_PN = "1";
"B":   PN = "2"  !CDS_PN = "2";
BODY = "Q_RES","I356": #LOCATION = "R805" !CDS_LOCATION = "R805" #SEC = "1" !CDS_SEC = "1";
"A":   PN = "1"  !CDS_PN = "1";
"B":   PN = "2"  !CDS_PN = "2";
BODY = "Q_RES","I360": LOCATION = "R309" #&CDS_LOCATION = "R309" &SEC = "1" #&CDS_SEC = "1";
"A":   PN = "1"  !CDS_PN = "1";
"B":   PN = "2"  !CDS_PN = "2";
BODY = "AST2600A3GP","I363": #LOCATION = "U5" !CDS_LOCATION = "U5" &SEC = "2" #&CDS_SEC = "2";
"FWSPICK":   PN = "AF13"  !CDS_PN = "AF13";
"FWSPICS0#":   PN = "AB14"  !CDS_PN = "AB14";
"FWSPICS1#":   PN = "AA13"  !CDS_PN = "AA13";
"FWSPICS2#":   PN = "AC13"  !CDS_PN = "AC13";
"FWSPIMISO":   PN = "AB13"  !CDS_PN = "AB13";
"FWSPIMOSI":   PN = "AC14"  !CDS_PN = "AC14";
"GPIOB0||SALT1":   PN = "J26"  !CDS_PN = "J26";
"GPIOB1||SALT2":   PN = "K23"  !CDS_PN = "K23";
"GPIOB2||SALT3":   PN = "H26"  !CDS_PN = "H26";
"GPIOB3||SALT4":   PN = "J25"  !CDS_PN = "J25";
"GPIOB4||MDC2":   PN = "J23"  !CDS_PN = "J23";
"GPIOB5||MDIO2":   PN = "G26"  !CDS_PN = "G26";
"GPIOB6||TXD4":   PN = "H25"  !CDS_PN = "H25";
"GPIOB7||RXD4":   PN = "J24"  !CDS_PN = "J24";
"GPIOI5||SIOPBO#":   PN = "E16"  !CDS_PN = "E16";
"GPIOI6||SIOPBI#":   PN = "B16"  !CDS_PN = "B16";
"GPIOI7||SIOSCI#":   PN = "A15"  !CDS_PN = "A15";
"GPIOL4||TXD3":   PN = "C15"  !CDS_PN = "C15";
"GPIOL5||RXD3":   PN = "F15"  !CDS_PN = "F15";
"GPIOM0||NCTS1":   PN = "D14"  !CDS_PN = "D14";
"GPIOM1||NDCD1":   PN = "B13"  !CDS_PN = "B13";
"GPIOM2||NDSR1":   PN = "A12"  !CDS_PN = "A12";
"GPIOM3||NRI1":   PN = "E14"  !CDS_PN = "E14";
"GPIOM4||NDTR1":   PN = "B12"  !CDS_PN = "B12";
"GPIOM5||NRTS1":   PN = "C12"  !CDS_PN = "C12";
"GPIOM6||TXD1":   PN = "C13"  !CDS_PN = "C13";
"GPIOM7||RXD1":   PN = "D13"  !CDS_PN = "D13";
"GPION0||NCTS2":   PN = "P25"  !CDS_PN = "P25";
"GPION1||NDCD2":   PN = "N23"  !CDS_PN = "N23";
"GPION2||NDSR2":   PN = "N25"  !CDS_PN = "N25";
"GPION3||NRI2":   PN = "N24"  !CDS_PN = "N24";
"GPION4||NDTR2":   PN = "P26"  !CDS_PN = "P26";
"GPION5||NRTS2":   PN = "M23"  !CDS_PN = "M23";
"GPION6||TXD2":   PN = "N26"  !CDS_PN = "N26";
"GPION7||RXD2":   PN = "M26"  !CDS_PN = "M26";
"GPIOS0||MDC1":   PN = "R23"  !CDS_PN = "R23";
"GPIOS1||MDIO1":   PN = "T25"  !CDS_PN = "T25";
"GPIOS4||TXD10":   PN = "R26"  !CDS_PN = "R26";
"GPIOS5||RXD10":   PN = "P24"  !CDS_PN = "P24";
"GPIOS6||TXD11":   PN = "P23"  !CDS_PN = "P23";
"GPIOS7||RXD11":   PN = "T24"  !CDS_PN = "T24";
"GPIOV0||SIOS3#":   PN = "AB15"  !CDS_PN = "AB15";
"GPIOV1||SIOS5#":   PN = "AF14"  !CDS_PN = "AF14";
"GPIOV2||SIOPWREQ#":   PN = "AD14"  !CDS_PN = "AD14";
"GPIOV3||SIOONCTRL#":   PN = "AC15"  !CDS_PN = "AC15";
"GPIOV4||SIOPWRGD":   PN = "AE15"  !CDS_PN = "AE15";
"GPIOV5||LPCPD#":   PN = "AE14"  !CDS_PN = "AE14";
"GPIOV6||LPCPME#":   PN = "AD15"  !CDS_PN = "AD15";
"GPIOV7||LPCSMI#":   PN = "AF15"  !CDS_PN = "AF15";
"GPIOX0||SPI2CS0#":   PN = "AE8"  !CDS_PN = "AE8";
"GPIOX1||SPI2CS1#":   PN = "AA9"  !CDS_PN = "AA9";
"GPIOX2||SPI2CS2#":   PN = "AC9"  !CDS_PN = "AC9";
"GPIOX3||SPI2CK":   PN = "AF8"  !CDS_PN = "AF8";
"GPIOX4||SPI2MOSI":   PN = "AB9"  !CDS_PN = "AB9";
"GPIOX5||SPI2MISO":   PN = "AD9"  !CDS_PN = "AD9";
"GPIOX6||SPI2DQ2||TXD12":   PN = "AF9"  !CDS_PN = "AF9";
"GPIOX7||SPI2DQ3||RXD12":   PN = "AB10"  !CDS_PN = "AB10";
"GPIOY0||SALT5||WDTRST1#":   PN = "AF11"  !CDS_PN = "AF11";
"GPIOY1||SALT6||WDTRST2#":   PN = "AD12"  !CDS_PN = "AD12";
"GPIOY2||SALT7||WDTRST3#":   PN = "AE11"  !CDS_PN = "AE11";
"GPIOY3||SALT8||WDTRST4#":   PN = "AA12"  !CDS_PN = "AA12";
"GPIOY4||FWSPIDQ2":   PN = "AE12"  !CDS_PN = "AE12";
"GPIOY5||FWSPIDQ3":   PN = "AF12"  !CDS_PN = "AF12";
"GPIOY6||FWSPIABR":   PN = "AC12"  !CDS_PN = "AC12";
"GPIOY7||FWSPIWP#":   PN = "AB12"  !CDS_PN = "AB12";
"GPIOZ0||SPI1CS1#":   PN = "AC10"  !CDS_PN = "AC10";
"GPIOZ1||SPI1ABR":   PN = "AD10"  !CDS_PN = "AD10";
"GPIOZ2||SPI1WP#":   PN = "AE10"  !CDS_PN = "AE10";
"GPIOZ3||SPI1CK":   PN = "AB11"  !CDS_PN = "AB11";
"GPIOZ4||SPI1MOSI":   PN = "AC11"  !CDS_PN = "AC11";
"GPIOZ5||SPI1MISO":   PN = "AA11"  !CDS_PN = "AA11";
"GPIOZ6||SPI1DQ2||TXD13":   PN = "AD11"  !CDS_PN = "AD11";
"GPIOZ7||SPI1DQ3||RXD13":   PN = "AF10"  !CDS_PN = "AF10";
"RGMII3RXCK||RMII3RCLKI||GPIOC6":   PN = "G23"  !CDS_PN = "G23";
"RGMII3RXCTL||GPIOC7":   PN = "G24"  !CDS_PN = "G24";
"RGMII3RXD0||RMII3RXD0||GPIOD0":   PN = "F23"  !CDS_PN = "F23";
"RGMII3RXD1||RMII3RXD1||GPIOD1":   PN = "F26"  !CDS_PN = "F26";
"RGMII3RXD2||RMII3CRSDV||GPIOD2":   PN = "F25"  !CDS_PN = "F25";
"RGMII3RXD3||RMII3RXER||GPIOD3":   PN = "E26"  !CDS_PN = "E26";
"RGMII3TXCK||RMII3RCLKO||GPIOC0":   PN = "H24"  !CDS_PN = "H24";
"RGMII3TXCTL||RMII3TXEN||GPIOC1":   PN = "J22"  !CDS_PN = "J22";
"RGMII3TXD0||RMII3TXD0||GPIOC2":   PN = "H22"  !CDS_PN = "H22";
"RGMII3TXD1||RMII3TXD1||GPIOC3":   PN = "H23"  !CDS_PN = "H23";
"RGMII3TXD2||GPIOC4":   PN = "G22"  !CDS_PN = "G22";
"RGMII3TXD3||GPIOC5":   PN = "F22"  !CDS_PN = "F22";
"RGMII4RXCK||RMII4RCLKI||NCTS4||GPIOE2":   PN = "C25"  !CDS_PN = "C25";
"RGMII4RXCTL||NDCD4||GPIOE3":   PN = "C26"  !CDS_PN = "C26";
"RGMII4RXD0||RMII4RXD0||NDSR4||GPIOE4":   PN = "C24"  !CDS_PN = "C24";
"RGMII4RXD1||RMII4RXD1||NRI4||GPIOE5":   PN = "B26"  !CDS_PN = "B26";
"RGMII4RXD2||RMII4CRSDV||NDTR4||GPIOE6":   PN = "B25"  !CDS_PN = "B25";
"RGMII4RXD3||RMII4RXER||NRTS4||GPIOE7":   PN = "B24"  !CDS_PN = "B24";
"RGMII4TXCK||RMII4RCLKO||NCTS3||GPIOD4":   PN = "F24"  !CDS_PN = "F24";
"RGMII4TXCTL||RMII4TXEN||NDCD3||GPIOD5":   PN = "E23"  !CDS_PN = "E23";
"RGMII4TXD0||RMII4TXD0||NDSR3||GPIOD6":   PN = "E24"  !CDS_PN = "E24";
"RGMII4TXD1||RMII4TXD1||NRI3||GPIOD7":   PN = "E25"  !CDS_PN = "E25";
"RGMII4TXD2||NDTR3||GPIOE0":   PN = "D26"  !CDS_PN = "D26";
"RGMII4TXD3||NRTS3||GPIOE1":   PN = "D24"  !CDS_PN = "D24";
"RGMIICK":   PN = "A10"  !CDS_PN = "A10";
"RXD5":   PN = "D8"  !CDS_PN = "D8";
"SPI1CS0#":   PN = "AD13"  !CDS_PN = "AD13";
"TXD5":   PN = "C8"  !CDS_PN = "C8";
BODY = "Q_RES","I365": #LOCATION = "R461" !CDS_LOCATION = "R461" &SEC = "1" #&CDS_SEC = "1";
"A":   PN = "1"  !CDS_PN = "1";
"B":   PN = "2"  !CDS_PN = "2";
BODY = "Q_RES","I373": LOCATION = "R402" #&CDS_LOCATION = "R402" &SEC = "1" #&CDS_SEC = "1";
"A":   PN = "1"  !CDS_PN = "1";
"B":   PN = "2"  !CDS_PN = "2";
BODY = "Q_RES","I374": LOCATION = "R401" #&CDS_LOCATION = "R401" &SEC = "1" #&CDS_SEC = "1";
"A":   PN = "1"  !CDS_PN = "1";
"B":   PN = "2"  !CDS_PN = "2";
BODY = "Q_RES","I381": #LOCATION = "R121" !CDS_LOCATION = "R121" &SEC = "1" #&CDS_SEC = "1";
"A":   PN = "1"  !CDS_PN = "1";
"B":   PN = "2"  !CDS_PN = "2";
BODY = "Q_RES","I382": #LOCATION = "R60" !CDS_LOCATION = "R60" &SEC = "1" #&CDS_SEC = "1";
"A":   PN = "1"  !CDS_PN = "1";
"B":   PN = "2"  !CDS_PN = "2";
BODY = "Q_RES","I383": #LOCATION = "R688" !CDS_LOCATION = "R688" &SEC = "1" #&CDS_SEC = "1";
"A":   PN = "1"  !CDS_PN = "1";
"B":   PN = "2"  !CDS_PN = "2";
BODY = "Q_RES","I384": #LOCATION = "R242" !CDS_LOCATION = "R242" &SEC = "1" #&CDS_SEC = "1";
"A":   PN = "1"  !CDS_PN = "1";
"B":   PN = "2"  !CDS_PN = "2";
BODY = "Q_RES","I398": #LOCATION = "R689" !CDS_LOCATION = "R689" &SEC = "1" #&CDS_SEC = "1";
"A":   PN = "1"  !CDS_PN = "1";
"B":   PN = "2"  !CDS_PN = "2";
BODY = "Q_RES","I399": #LOCATION = "R122" !CDS_LOCATION = "R122" &SEC = "1" #&CDS_SEC = "1";
"A":   PN = "1"  !CDS_PN = "1";
"B":   PN = "2"  !CDS_PN = "2";
BODY = "Q_RES","I400": #LOCATION = "R760" !CDS_LOCATION = "R760" &SEC = "1" #&CDS_SEC = "1";
"A":   PN = "1"  !CDS_PN = "1";
"B":   PN = "2"  !CDS_PN = "2";
BODY = "Q_RES","I402": #LOCATION = "R763" !CDS_LOCATION = "R763" &SEC = "1" #&CDS_SEC = "1";
"A":   PN = "1"  !CDS_PN = "1";
"B":   PN = "2"  !CDS_PN = "2";
BODY = "Q_RES","I407": #LOCATION = "R458" !CDS_LOCATION = "R458" &SEC = "1" #&CDS_SEC = "1";
"A":   PN = "1"  !CDS_PN = "1";
"B":   PN = "2"  !CDS_PN = "2";
BODY = "Q_RES","I419": #LOCATION = "R70" !CDS_LOCATION = "R70" #SEC = "1" !CDS_SEC = "1";
"A":   PN = "1"  !CDS_PN = "1";
"B":   PN = "2"  !CDS_PN = "2";
BODY = "Q_RES","I421": #LOCATION = "R65" !CDS_LOCATION = "R65" #SEC = "1" !CDS_SEC = "1";
"A":   PN = "1"  !CDS_PN = "1";
"B":   PN = "2"  !CDS_PN = "2";
BODY = "Q_RES","I427": #LOCATION = "R112" !CDS_LOCATION = "R112" &SEC = "1" #&CDS_SEC = "1";
"A":   PN = "1"  !CDS_PN = "1";
"B":   PN = "2"  !CDS_PN = "2";
BODY = "Q_RES","I430": #LOCATION = "R405" !CDS_LOCATION = "R405" &SEC = "1" #&CDS_SEC = "1";
"A":   PN = "1"  !CDS_PN = "1";
"B":   PN = "2"  !CDS_PN = "2";
BODY = "Q_RES","I431": #LOCATION = "R466" !CDS_LOCATION = "R466" &SEC = "1" #&CDS_SEC = "1";
"A":   PN = "1"  !CDS_PN = "1";
"B":   PN = "2"  !CDS_PN = "2";
BODY = "Q_RES","I432": #LOCATION = "R465" !CDS_LOCATION = "R465" &SEC = "1" #&CDS_SEC = "1";
"A":   PN = "1"  !CDS_PN = "1";
"B":   PN = "2"  !CDS_PN = "2";
BODY = "74LVC1G66GV","I435": LOCATION = "U28" #&CDS_LOCATION = "U28" &SEC = "1" #&CDS_SEC = "1";
"E":   PN = "4"  !CDS_PN = "4";
"GND":   PN = "3"  !CDS_PN = "3";
"VCC":   PN = "5"  !CDS_PN = "5";
"Y":   PN = "1"  !CDS_PN = "1";
"Z":   PN = "2"  !CDS_PN = "2";
BODY = "Q_CAP","I440": LOCATION = "C180" #&CDS_LOCATION = "C180" &SEC = "1" #&CDS_SEC = "1";
"A":   PN = "1"  !CDS_PN = "1";
"B":   PN = "2"  !CDS_PN = "2";
BODY = "Q_RES","I447": #LOCATION = "R392" !CDS_LOCATION = "R392" &SEC = "1" #&CDS_SEC = "1";
"A":   PN = "1"  !CDS_PN = "1";
"B":   PN = "2"  !CDS_PN = "2";
BODY = "Q_RES","I448": LOCATION = "R395" #&CDS_LOCATION = "R395" &SEC = "1" #&CDS_SEC = "1";
"A":   PN = "1"  !CDS_PN = "1";
"B":   PN = "2"  !CDS_PN = "2";
BODY = "Q_RES","I449": #LOCATION = "R468" !CDS_LOCATION = "R468" &SEC = "1" #&CDS_SEC = "1";
"A":   PN = "1"  !CDS_PN = "1";
"B":   PN = "2"  !CDS_PN = "2";
BODY = "Q_RES","I451": #LOCATION = "R171" !CDS_LOCATION = "R171" &SEC = "1" #&CDS_SEC = "1";
"A":   PN = "1"  !CDS_PN = "1";
"B":   PN = "2"  !CDS_PN = "2";
BODY = "Q_RES","I452": #LOCATION = "R172" !CDS_LOCATION = "R172" &SEC = "1" #&CDS_SEC = "1";
"A":   PN = "1"  !CDS_PN = "1";
"B":   PN = "2"  !CDS_PN = "2";
BODY = "Q_RES","I453": #LOCATION = "R173" !CDS_LOCATION = "R173" &SEC = "1" #&CDS_SEC = "1";
"A":   PN = "1"  !CDS_PN = "1";
"B":   PN = "2"  !CDS_PN = "2";
DRAWING = "@scm_lib.scm(sch_1):page14";
BODY = "AST2600A3GP","I149": #LOCATION = "U5" !CDS_LOCATION = "U5" &SEC = "3" #&CDS_SEC = "3";
"GPIO18D0||EMMCCLK":   PN = "AB4"  !CDS_PN = "AB4";
"GPIO18D1||EMMCCMD":   PN = "AA4"  !CDS_PN = "AA4";
"GPIO18D2||EMMCDAT0":   PN = "AC4"  !CDS_PN = "AC4";
"GPIO18D3||EMMCDAT1":   PN = "AA5"  !CDS_PN = "AA5";
"GPIO18D4||EMMCDAT2":   PN = "Y5"  !CDS_PN = "Y5";
"GPIO18D5||EMMCDAT3":   PN = "AB5"  !CDS_PN = "AB5";
"GPIO18D6||EMMCCD#":   PN = "AC5"  !CDS_PN = "AC5";
"GPIO18D7||EMMCWP#":   PN = "AB6"  !CDS_PN = "AB6";
"GPIO18E0||EMMCDAT4||FWSPI18CS#||VBCS#":   PN = "Y1"  !CDS_PN = "Y1";
"GPIO18E1||EMMCDAT5||FWSPI18CK||VBCK":   PN = "Y2"  !CDS_PN = "Y2";
"GPIO18E2||EMMCDAT6||FWSPI18MOSI||VBMOSI":   PN = "Y3"  !CDS_PN = "Y3";
"GPIO18E3||EMMCDAT7||FWSPI18MISO||VBMISO":   PN = "Y4"  !CDS_PN = "Y4";
"I3C1SCL":   PN = "AF23"  !CDS_PN = "AF23";
"I3C1SDA":   PN = "AE24"  !CDS_PN = "AE24";
"I3C2SCL":   PN = "AF22"  !CDS_PN = "AF22";
"I3C2SDA":   PN = "AE22"  !CDS_PN = "AE22";
"I3C3SCL||FSI1CLK":   PN = "AF25"  !CDS_PN = "AF25";
"I3C3SDA||FSI1DATA":   PN = "AE26"  !CDS_PN = "AE26";
"I3C4SCL||FSI2CLK":   PN = "AE25"  !CDS_PN = "AE25";
"I3C4SDA||FSI2DATA":   PN = "AF24"  !CDS_PN = "AF24";
"RGMII1RXCK||RMII1RCLKI||GPIO18A6":   PN = "B3"  !CDS_PN = "B3";
"RGMII1RXCTL||GPIO18A7":   PN = "A2"  !CDS_PN = "A2";
"RGMII1RXD0||RMII1RXD0||GPIO18B0":   PN = "B2"  !CDS_PN = "B2";
"RGMII1RXD1||RMII1RXD1||GPIO18B1":   PN = "B1"  !CDS_PN = "B1";
"RGMII1RXD2||RMII1CRSDV||GPIO18B2":   PN = "C4"  !CDS_PN = "C4";
"RGMII1RXD3||RMII1RXER||GPIO18B3":   PN = "E5"  !CDS_PN = "E5";
"RGMII1TXCK||RMII1RCLKO||GPIO18A0":   PN = "C6"  !CDS_PN = "C6";
"RGMII1TXCTL||RMII1TXEN||GPIO18A1":   PN = "D6"  !CDS_PN = "D6";
"RGMII1TXD0||RMII1TXD0||GPIO18A2":   PN = "D5"  !CDS_PN = "D5";
"RGMII1TXD1||RMII1TXD1||GPIO18A3":   PN = "A3"  !CDS_PN = "A3";
"RGMII1TXD2||GPIO18A4":   PN = "C5"  !CDS_PN = "C5";
"RGMII1TXD3||GPIO18A5":   PN = "E6"  !CDS_PN = "E6";
"RGMII2RXCK||RMII2RCLKI||GPIO18C2":   PN = "D2"  !CDS_PN = "D2";
"RGMII2RXCTL||GPIO18C3":   PN = "E3"  !CDS_PN = "E3";
"RGMII2RXD0||RMII2RXD0||GPIO18C4":   PN = "D1"  !CDS_PN = "D1";
"RGMII2RXD1||RMII2RXD1||GPIO18C5":   PN = "F4"  !CDS_PN = "F4";
"RGMII2RXD2||RMII2CRSDV||GPIO18C6":   PN = "E2"  !CDS_PN = "E2";
"RGMII2RXD3||RMII2RXER||GPIO18C7":   PN = "E1"  !CDS_PN = "E1";
"RGMII2TXCK||RMII2RCLKO||GPIO18B4":   PN = "D4"  !CDS_PN = "D4";
"RGMII2TXCTL||RMII2TXEN||GPIO18B5":   PN = "C2"  !CDS_PN = "C2";
"RGMII2TXD0||RMII2TXD0||GPIO18B6":   PN = "C1"  !CDS_PN = "C1";
"RGMII2TXD1||RMII2TXD1||GPIO18B7":   PN = "D3"  !CDS_PN = "D3";
"RGMII2TXD2||GPIO18C0":   PN = "E4"  !CDS_PN = "E4";
"RGMII2TXD3||GPIO18C1":   PN = "F5"  !CDS_PN = "F5";
BODY = "Q_RES","I163": #LOCATION = "R684" !CDS_LOCATION = "R684" #SEC = "1" !CDS_SEC = "1";
"A":   PN = "1"  !CDS_PN = "1";
"B":   PN = "2"  !CDS_PN = "2";
BODY = "Q_RES","I164": #LOCATION = "R686" !CDS_LOCATION = "R686" &SEC = "1" #&CDS_SEC = "1";
"A":   PN = "1"  !CDS_PN = "1";
"B":   PN = "2"  !CDS_PN = "2";
BODY = "Q_RES","I165": #LOCATION = "R685" !CDS_LOCATION = "R685" #SEC = "1" !CDS_SEC = "1";
"A":   PN = "1"  !CDS_PN = "1";
"B":   PN = "2"  !CDS_PN = "2";
BODY = "Q_RES","I166": #LOCATION = "R687" !CDS_LOCATION = "R687" &SEC = "1" #&CDS_SEC = "1";
"A":   PN = "1"  !CDS_PN = "1";
"B":   PN = "2"  !CDS_PN = "2";
BODY = "Q_RES","I171": #LOCATION = "R194" !CDS_LOCATION = "R194" &SEC = "1" #&CDS_SEC = "1";
"A":   PN = "1"  !CDS_PN = "1";
"B":   PN = "2"  !CDS_PN = "2";
BODY = "Q_RES","I172": #LOCATION = "R195" !CDS_LOCATION = "R195" &SEC = "1" #&CDS_SEC = "1";
"A":   PN = "1"  !CDS_PN = "1";
"B":   PN = "2"  !CDS_PN = "2";
BODY = "Q_RES","I173": #LOCATION = "R190" !CDS_LOCATION = "R190" &SEC = "1" #&CDS_SEC = "1";
"A":   PN = "1"  !CDS_PN = "1";
"B":   PN = "2"  !CDS_PN = "2";
BODY = "Q_RES","I174": #LOCATION = "R191" !CDS_LOCATION = "R191" &SEC = "1" #&CDS_SEC = "1";
"A":   PN = "1"  !CDS_PN = "1";
"B":   PN = "2"  !CDS_PN = "2";
BODY = "Q_RES","I183": #LOCATION = "R188" !CDS_LOCATION = "R188" &SEC = "1" #&CDS_SEC = "1";
"A":   PN = "1"  !CDS_PN = "1";
"B":   PN = "2"  !CDS_PN = "2";
BODY = "Q_RES","I188": #LOCATION = "R189" !CDS_LOCATION = "R189" &SEC = "1" #&CDS_SEC = "1";
"A":   PN = "1"  !CDS_PN = "1";
"B":   PN = "2"  !CDS_PN = "2";
BODY = "Q_RES","I189": #LOCATION = "R196" !CDS_LOCATION = "R196" &SEC = "1" #&CDS_SEC = "1";
"A":   PN = "1"  !CDS_PN = "1";
"B":   PN = "2"  !CDS_PN = "2";
BODY = "Q_RES","I190": #LOCATION = "R197" !CDS_LOCATION = "R197" &SEC = "1" #&CDS_SEC = "1";
"A":   PN = "1"  !CDS_PN = "1";
"B":   PN = "2"  !CDS_PN = "2";
BODY = "Q_RES","I220": #LOCATION = "R856" !CDS_LOCATION = "R856" &SEC = "1" #&CDS_SEC = "1";
"A":   PN = "1"  !CDS_PN = "1";
"B":   PN = "2"  !CDS_PN = "2";
BODY = "Q_RES","I221": #LOCATION = "R854" !CDS_LOCATION = "R854" &SEC = "1" #&CDS_SEC = "1";
"A":   PN = "1"  !CDS_PN = "1";
"B":   PN = "2"  !CDS_PN = "2";
BODY = "Q_RES","I222": #LOCATION = "R858" !CDS_LOCATION = "R858" &SEC = "1" #&CDS_SEC = "1";
"A":   PN = "1"  !CDS_PN = "1";
"B":   PN = "2"  !CDS_PN = "2";
BODY = "Q_RES","I223": #LOCATION = "R855" !CDS_LOCATION = "R855" &SEC = "1" #&CDS_SEC = "1";
"A":   PN = "1"  !CDS_PN = "1";
"B":   PN = "2"  !CDS_PN = "2";
BODY = "Q_RES","I224": #LOCATION = "R857" !CDS_LOCATION = "R857" &SEC = "1" #&CDS_SEC = "1";
"A":   PN = "1"  !CDS_PN = "1";
"B":   PN = "2"  !CDS_PN = "2";
BODY = "Q_RES","I225": #LOCATION = "R865" !CDS_LOCATION = "R865" &SEC = "1" #&CDS_SEC = "1";
"A":   PN = "1"  !CDS_PN = "1";
"B":   PN = "2"  !CDS_PN = "2";
BODY = "Q_RES","I229": LOCATION = "R884" #&CDS_LOCATION = "R884" &SEC = "1" #&CDS_SEC = "1";
"A":   PN = "1"  !CDS_PN = "1";
"B":   PN = "2"  !CDS_PN = "2";
BODY = "Q_RES","I231": LOCATION = "R885" #&CDS_LOCATION = "R885" &SEC = "1" #&CDS_SEC = "1";
"A":   PN = "1"  !CDS_PN = "1";
"B":   PN = "2"  !CDS_PN = "2";
BODY = "Q_RES","I232": #LOCATION = "R184" !CDS_LOCATION = "R184" &SEC = "1" #&CDS_SEC = "1";
"A":   PN = "1"  !CDS_PN = "1";
"B":   PN = "2"  !CDS_PN = "2";
BODY = "Q_RES","I233": #LOCATION = "R186" !CDS_LOCATION = "R186" &SEC = "1" #&CDS_SEC = "1";
"A":   PN = "1"  !CDS_PN = "1";
"B":   PN = "2"  !CDS_PN = "2";
BODY = "Q_RES","I234": #LOCATION = "R198" !CDS_LOCATION = "R198" &SEC = "1" #&CDS_SEC = "1";
"A":   PN = "1"  !CDS_PN = "1";
"B":   PN = "2"  !CDS_PN = "2";
BODY = "Q_RES","I235": #LOCATION = "R200" !CDS_LOCATION = "R200" &SEC = "1" #&CDS_SEC = "1";
"A":   PN = "1"  !CDS_PN = "1";
"B":   PN = "2"  !CDS_PN = "2";
BODY = "Q_RES","I236": #LOCATION = "R185" !CDS_LOCATION = "R185" &SEC = "1" #&CDS_SEC = "1";
"A":   PN = "1"  !CDS_PN = "1";
"B":   PN = "2"  !CDS_PN = "2";
BODY = "Q_RES","I237": #LOCATION = "R187" !CDS_LOCATION = "R187" &SEC = "1" #&CDS_SEC = "1";
"A":   PN = "1"  !CDS_PN = "1";
"B":   PN = "2"  !CDS_PN = "2";
BODY = "Q_RES","I238": #LOCATION = "R199" !CDS_LOCATION = "R199" &SEC = "1" #&CDS_SEC = "1";
"A":   PN = "1"  !CDS_PN = "1";
"B":   PN = "2"  !CDS_PN = "2";
BODY = "Q_RES","I239": #LOCATION = "R201" !CDS_LOCATION = "R201" &SEC = "1" #&CDS_SEC = "1";
"A":   PN = "1"  !CDS_PN = "1";
"B":   PN = "2"  !CDS_PN = "2";
DRAWING = "@scm_lib.scm(sch_1):page15";
BODY = "Q_RES","I2": #LOCATION = "R208" !CDS_LOCATION = "R208" &SEC = "1" #&CDS_SEC = "1";
"A":   PN = "1"  !CDS_PN = "1";
"B":   PN = "2"  !CDS_PN = "2";
BODY = "Q_RES","I4": #LOCATION = "R207" !CDS_LOCATION = "R207" &SEC = "1" #&CDS_SEC = "1";
"A":   PN = "1"  !CDS_PN = "1";
"B":   PN = "2"  !CDS_PN = "2";
BODY = "Q_CAP","I14": #LOCATION = "C35" !CDS_LOCATION = "C35" &SEC = "1" #&CDS_SEC = "1";
"A":   PN = "1"  !CDS_PN = "1";
"B":   PN = "2"  !CDS_PN = "2";
BODY = "Q_CAP","I16": #LOCATION = "C36" !CDS_LOCATION = "C36" &SEC = "1" #&CDS_SEC = "1";
"A":   PN = "1"  !CDS_PN = "1";
"B":   PN = "2"  !CDS_PN = "2";
BODY = "Q_RES","I19": #LOCATION = "R209" !CDS_LOCATION = "R209" &SEC = "1" #&CDS_SEC = "1";
"A":   PN = "1"  !CDS_PN = "1";
"B":   PN = "2"  !CDS_PN = "2";
BODY = "Q_RES","I21": #LOCATION = "R212" !CDS_LOCATION = "R212" &SEC = "1" #&CDS_SEC = "1";
"A":   PN = "1"  !CDS_PN = "1";
"B":   PN = "2"  !CDS_PN = "2";
BODY = "Q_CAP","I24": #LOCATION = "C37" !CDS_LOCATION = "C37" &SEC = "1" #&CDS_SEC = "1";
"A":   PN = "1"  !CDS_PN = "1";
"B":   PN = "2"  !CDS_PN = "2";
BODY = "Q_RES","I32": #LOCATION = "R214" !CDS_LOCATION = "R214" &SEC = "1" #&CDS_SEC = "1";
"A":   PN = "1"  !CDS_PN = "1";
"B":   PN = "2"  !CDS_PN = "2";
BODY = "Q_RES","I34": #LOCATION = "R213" !CDS_LOCATION = "R213" &SEC = "1" #&CDS_SEC = "1";
"A":   PN = "1"  !CDS_PN = "1";
"B":   PN = "2"  !CDS_PN = "2";
BODY = "Q_CAP","I36": #LOCATION = "C38" !CDS_LOCATION = "C38" &SEC = "1" #&CDS_SEC = "1";
"A":   PN = "1"  !CDS_PN = "1";
"B":   PN = "2"  !CDS_PN = "2";
BODY = "Q_CAP","I37": #LOCATION = "C39" !CDS_LOCATION = "C39" &SEC = "1" #&CDS_SEC = "1";
"A":   PN = "1"  !CDS_PN = "1";
"B":   PN = "2"  !CDS_PN = "2";
BODY = "OSC4_7X25000018","I39": #LOCATION = "OSC1" !CDS_LOCATION = "OSC1" &SEC = "1" #&CDS_SEC = "1";
"GND":   PN = "2"  !CDS_PN = "2";
"OE":   PN = "1"  !CDS_PN = "1";
"OUT":   PN = "3"  !CDS_PN = "3";
"VDD":   PN = "4"  !CDS_PN = "4";
BODY = "Q_RES","I42": #LOCATION = "R215" !CDS_LOCATION = "R215" &SEC = "1" #&CDS_SEC = "1";
"A":   PN = "1"  !CDS_PN = "1";
"B":   PN = "2"  !CDS_PN = "2";
BODY = "Q_RES","I47": #LOCATION = "R210" !CDS_LOCATION = "R210" #SEC = "1" !CDS_SEC = "1";
"A":   PN = "1"  !CDS_PN = "1";
"B":   PN = "2"  !CDS_PN = "2";
BODY = "Q_RES","I51": #LOCATION = "R211" !CDS_LOCATION = "R211" &SEC = "1" #&CDS_SEC = "1";
"A":   PN = "1"  !CDS_PN = "1";
"B":   PN = "2"  !CDS_PN = "2";
BODY = "Q_INDUCTOR","I65": #LOCATION = "L3" !CDS_LOCATION = "L3" &SEC = "1" #&CDS_SEC = "1";
"1":   PN = "1"  !CDS_PN = "1";
"2":   PN = "2"  !CDS_PN = "2";
BODY = "Q_CAP","I68": #LOCATION = "C41" !CDS_LOCATION = "C41" &SEC = "1" #&CDS_SEC = "1";
"A":   PN = "1"  !CDS_PN = "1";
"B":   PN = "2"  !CDS_PN = "2";
BODY = "Q_INDUCTOR","I82": #LOCATION = "L4" !CDS_LOCATION = "L4" &SEC = "1" #&CDS_SEC = "1";
"1":   PN = "1"  !CDS_PN = "1";
"2":   PN = "2"  !CDS_PN = "2";
BODY = "Q_CAP","I89": #LOCATION = "C45" !CDS_LOCATION = "C45" &SEC = "1" #&CDS_SEC = "1";
"A":   PN = "1"  !CDS_PN = "1";
"B":   PN = "2"  !CDS_PN = "2";
BODY = "Q_RES","I92": #LOCATION = "R217" !CDS_LOCATION = "R217" &SEC = "1" #&CDS_SEC = "1";
"A":   PN = "1"  !CDS_PN = "1";
"B":   PN = "2"  !CDS_PN = "2";
BODY = "Q_RES","I93": #LOCATION = "R218" !CDS_LOCATION = "R218" &SEC = "1" #&CDS_SEC = "1";
"A":   PN = "1"  !CDS_PN = "1";
"B":   PN = "2"  !CDS_PN = "2";
BODY = "Q_CAP","I117": #LOCATION = "C42" !CDS_LOCATION = "C42" &SEC = "1" #&CDS_SEC = "1";
"A":   PN = "1"  !CDS_PN = "1";
"B":   PN = "2"  !CDS_PN = "2";
BODY = "Q_CAP","I119": #LOCATION = "C43" !CDS_LOCATION = "C43" &SEC = "1" #&CDS_SEC = "1";
"A":   PN = "1"  !CDS_PN = "1";
"B":   PN = "2"  !CDS_PN = "2";
BODY = "Q_RES","I128": #LOCATION = "R566" !CDS_LOCATION = "R566" &SEC = "1" #&CDS_SEC = "1";
"A":   PN = "1"  !CDS_PN = "1";
"B":   PN = "2"  !CDS_PN = "2";
BODY = "Q_RES","I133": #LOCATION = "R21" !CDS_LOCATION = "R21" &SEC = "1" #&CDS_SEC = "1";
"A":   PN = "1"  !CDS_PN = "1";
"B":   PN = "2"  !CDS_PN = "2";
BODY = "Q_RES","I134": #LOCATION = "R24" !CDS_LOCATION = "R24" &SEC = "1" #&CDS_SEC = "1";
"A":   PN = "1"  !CDS_PN = "1";
"B":   PN = "2"  !CDS_PN = "2";
BODY = "Q_RES","I140": #LOCATION = "R20" !CDS_LOCATION = "R20" &SEC = "1" #&CDS_SEC = "1";
"A":   PN = "1"  !CDS_PN = "1";
"B":   PN = "2"  !CDS_PN = "2";
BODY = "Q_RES","I141": #LOCATION = "R19" !CDS_LOCATION = "R19" &SEC = "1" #&CDS_SEC = "1";
"A":   PN = "1"  !CDS_PN = "1";
"B":   PN = "2"  !CDS_PN = "2";
BODY = "Q_RES","I142": #LOCATION = "R26" !CDS_LOCATION = "R26" &SEC = "1" #&CDS_SEC = "1";
"A":   PN = "1"  !CDS_PN = "1";
"B":   PN = "2"  !CDS_PN = "2";
BODY = "Q_RES","I149": #LOCATION = "R25" !CDS_LOCATION = "R25" &SEC = "1" #&CDS_SEC = "1";
"A":   PN = "1"  !CDS_PN = "1";
"B":   PN = "2"  !CDS_PN = "2";
BODY = "Q_RES","I150": #LOCATION = "R23" !CDS_LOCATION = "R23" &SEC = "1" #&CDS_SEC = "1";
"A":   PN = "1"  !CDS_PN = "1";
"B":   PN = "2"  !CDS_PN = "2";
BODY = "Q_RES","I151": #LOCATION = "R22" !CDS_LOCATION = "R22" &SEC = "1" #&CDS_SEC = "1";
"A":   PN = "1"  !CDS_PN = "1";
"B":   PN = "2"  !CDS_PN = "2";
BODY = "Q_RES","I152": #LOCATION = "R623" !CDS_LOCATION = "R623" &SEC = "1" #&CDS_SEC = "1";
"A":   PN = "1"  !CDS_PN = "1";
"B":   PN = "2"  !CDS_PN = "2";
BODY = "Q_RES","I168": #LOCATION = "R528" !CDS_LOCATION = "R528" &SEC = "1" #&CDS_SEC = "1";
"A":   PN = "1"  !CDS_PN = "1";
"B":   PN = "2"  !CDS_PN = "2";
BODY = "Q_RES","I169": #LOCATION = "R527" !CDS_LOCATION = "R527" &SEC = "1" #&CDS_SEC = "1";
"A":   PN = "1"  !CDS_PN = "1";
"B":   PN = "2"  !CDS_PN = "2";
BODY = "Q_RES","I174": #LOCATION = "R717" !CDS_LOCATION = "R717" &SEC = "1" #&CDS_SEC = "1";
"A":   PN = "1"  !CDS_PN = "1";
"B":   PN = "2"  !CDS_PN = "2";
BODY = "MOSFET_N_GSD","I179": #LOCATION = "Q11" !CDS_LOCATION = "Q11" &SEC = "1" #&CDS_SEC = "1";
"DRAIN":   PN = "D"  !CDS_PN = "D";
"GATE":   PN = "G"  !CDS_PN = "G";
"SOURCE":   PN = "S"  !CDS_PN = "S";
BODY = "Q_CAP","I180": #LOCATION = "C275" !CDS_LOCATION = "C275" &SEC = "1" #&CDS_SEC = "1";
"A":   PN = "1"  !CDS_PN = "1";
"B":   PN = "2"  !CDS_PN = "2";
BODY = "Q_RES","I181": #LOCATION = "R778" !CDS_LOCATION = "R778" &SEC = "1" #&CDS_SEC = "1";
"A":   PN = "1"  !CDS_PN = "1";
"B":   PN = "2"  !CDS_PN = "2";
BODY = "Q_RES","I183": #LOCATION = "R775" !CDS_LOCATION = "R775" &SEC = "1" #&CDS_SEC = "1";
"A":   PN = "1"  !CDS_PN = "1";
"B":   PN = "2"  !CDS_PN = "2";
BODY = "Q_RES","I184": #LOCATION = "R776" !CDS_LOCATION = "R776" #SEC = "1" !CDS_SEC = "1";
"A":   PN = "1"  !CDS_PN = "1";
"B":   PN = "2"  !CDS_PN = "2";
BODY = "Q_CAP","I201": #LOCATION = "C290" !CDS_LOCATION = "C290" &SEC = "1" #&CDS_SEC = "1";
"A":   PN = "1"  !CDS_PN = "1";
"B":   PN = "2"  !CDS_PN = "2";
BODY = "Q_RES","I202": #LOCATION = "R785" !CDS_LOCATION = "R785" &SEC = "1" #&CDS_SEC = "1";
"A":   PN = "1"  !CDS_PN = "1";
"B":   PN = "2"  !CDS_PN = "2";
BODY = "Q_RES","I203": #LOCATION = "R786" !CDS_LOCATION = "R786" &SEC = "1" #&CDS_SEC = "1";
"A":   PN = "1"  !CDS_PN = "1";
"B":   PN = "2"  !CDS_PN = "2";
BODY = "Q_CAP","I207": #LOCATION = "C295" !CDS_LOCATION = "C295" &SEC = "1" #&CDS_SEC = "1";
"A":   PN = "1"  !CDS_PN = "1";
"B":   PN = "2"  !CDS_PN = "2";
BODY = "Q_RES","I211": #LOCATION = "R788" !CDS_LOCATION = "R788" &SEC = "1" #&CDS_SEC = "1";
"A":   PN = "1"  !CDS_PN = "1";
"B":   PN = "2"  !CDS_PN = "2";
BODY = "Q_CAP","I215": #LOCATION = "C299" !CDS_LOCATION = "C299" &SEC = "1" #&CDS_SEC = "1";
"A":   PN = "1"  !CDS_PN = "1";
"B":   PN = "2"  !CDS_PN = "2";
BODY = "Q_RES","I219": #LOCATION = "R789" !CDS_LOCATION = "R789" &SEC = "1" #&CDS_SEC = "1";
"A":   PN = "1"  !CDS_PN = "1";
"B":   PN = "2"  !CDS_PN = "2";
BODY = "Q_RES","I220": #LOCATION = "R790" !CDS_LOCATION = "R790" &SEC = "1" #&CDS_SEC = "1";
"A":   PN = "1"  !CDS_PN = "1";
"B":   PN = "2"  !CDS_PN = "2";
BODY = "Q_RES","I223": #LOCATION = "R787" !CDS_LOCATION = "R787" &SEC = "1" #&CDS_SEC = "1";
"A":   PN = "1"  !CDS_PN = "1";
"B":   PN = "2"  !CDS_PN = "2";
BODY = "Q_CAP","I235": #LOCATION = "C303" !CDS_LOCATION = "C303" &SEC = "1" #&CDS_SEC = "1";
"A":   PN = "1"  !CDS_PN = "1";
"B":   PN = "2"  !CDS_PN = "2";
BODY = "Q_RES","I236": #LOCATION = "R792" !CDS_LOCATION = "R792" &SEC = "1" #&CDS_SEC = "1";
"A":   PN = "1"  !CDS_PN = "1";
"B":   PN = "2"  !CDS_PN = "2";
BODY = "Q_CAP","I240": #LOCATION = "C307" !CDS_LOCATION = "C307" &SEC = "1" #&CDS_SEC = "1";
"A":   PN = "1"  !CDS_PN = "1";
"B":   PN = "2"  !CDS_PN = "2";
BODY = "Q_RES","I242": #LOCATION = "R794" !CDS_LOCATION = "R794" &SEC = "1" #&CDS_SEC = "1";
"A":   PN = "1"  !CDS_PN = "1";
"B":   PN = "2"  !CDS_PN = "2";
BODY = "Q_RES","I244": #LOCATION = "R793" !CDS_LOCATION = "R793" &SEC = "1" #&CDS_SEC = "1";
"A":   PN = "1"  !CDS_PN = "1";
"B":   PN = "2"  !CDS_PN = "2";
BODY = "Q_RES","I245": #LOCATION = "R791" !CDS_LOCATION = "R791" &SEC = "1" #&CDS_SEC = "1";
"A":   PN = "1"  !CDS_PN = "1";
"B":   PN = "2"  !CDS_PN = "2";
BODY = "Q_CAP","I247": #LOCATION = "C309" !CDS_LOCATION = "C309" &SEC = "1" #&CDS_SEC = "1";
"A":   PN = "1"  !CDS_PN = "1";
"B":   PN = "2"  !CDS_PN = "2";
BODY = "Q_RES","I252": #LOCATION = "R795" !CDS_LOCATION = "R795" &SEC = "1" #&CDS_SEC = "1";
"A":   PN = "1"  !CDS_PN = "1";
"B":   PN = "2"  !CDS_PN = "2";
BODY = "Q_RES","I255": #LOCATION = "R796" !CDS_LOCATION = "R796" &SEC = "1" #&CDS_SEC = "1";
"A":   PN = "1"  !CDS_PN = "1";
"B":   PN = "2"  !CDS_PN = "2";
BODY = "Q_CAP","I256": #LOCATION = "C311" !CDS_LOCATION = "C311" &SEC = "1" #&CDS_SEC = "1";
"A":   PN = "1"  !CDS_PN = "1";
"B":   PN = "2"  !CDS_PN = "2";
BODY = "Q_CAP","I259": #LOCATION = "C314" !CDS_LOCATION = "C314" &SEC = "1" #&CDS_SEC = "1";
"A":   PN = "1"  !CDS_PN = "1";
"B":   PN = "2"  !CDS_PN = "2";
BODY = "Q_RES","I261": #LOCATION = "R797" !CDS_LOCATION = "R797" &SEC = "1" #&CDS_SEC = "1";
"A":   PN = "1"  !CDS_PN = "1";
"B":   PN = "2"  !CDS_PN = "2";
BODY = "Q_RES","I262": #LOCATION = "R798" !CDS_LOCATION = "R798" &SEC = "1" #&CDS_SEC = "1";
"A":   PN = "1"  !CDS_PN = "1";
"B":   PN = "2"  !CDS_PN = "2";
BODY = "Q_RES","I289": #LOCATION = "R777" !CDS_LOCATION = "R777" &SEC = "1" #&CDS_SEC = "1";
"A":   PN = "1"  !CDS_PN = "1";
"B":   PN = "2"  !CDS_PN = "2";
BODY = "Q_RES","I318": #LOCATION = "R316" !CDS_LOCATION = "R316" &SEC = "1" #&CDS_SEC = "1";
"A":   PN = "1"  !CDS_PN = "1";
"B":   PN = "2"  !CDS_PN = "2";
BODY = "Q_RES","I320": #LOCATION = "R448" !CDS_LOCATION = "R448" &SEC = "1" #&CDS_SEC = "1";
"A":   PN = "1"  !CDS_PN = "1";
"B":   PN = "2"  !CDS_PN = "2";
BODY = "Q_RES","I321": #LOCATION = "R449" !CDS_LOCATION = "R449" &SEC = "1" #&CDS_SEC = "1";
"A":   PN = "1"  !CDS_PN = "1";
"B":   PN = "2"  !CDS_PN = "2";
BODY = "Q_RES","I326": #LOCATION = "R489" !CDS_LOCATION = "R489" &SEC = "1" #&CDS_SEC = "1";
"A":   PN = "1"  !CDS_PN = "1";
"B":   PN = "2"  !CDS_PN = "2";
BODY = "Q_RES","I330": #LOCATION = "R479" !CDS_LOCATION = "R479" &SEC = "1" #&CDS_SEC = "1";
"A":   PN = "1"  !CDS_PN = "1";
"B":   PN = "2"  !CDS_PN = "2";
BODY = "Q_RES","I345": #LOCATION = "R644" !CDS_LOCATION = "R644" &SEC = "1" #&CDS_SEC = "1";
"A":   PN = "1"  !CDS_PN = "1";
"B":   PN = "2"  !CDS_PN = "2";
BODY = "Q_RES","I346": #LOCATION = "R491" !CDS_LOCATION = "R491" &SEC = "1" #&CDS_SEC = "1";
"A":   PN = "1"  !CDS_PN = "1";
"B":   PN = "2"  !CDS_PN = "2";
BODY = "AST2600A3GP","I350": #LOCATION = "U5" !CDS_LOCATION = "U5" &SEC = "4" #&CDS_SEC = "4";
"ADC0||GPIT0":   PN = "AD20"  !CDS_PN = "AD20";
"ADC1||GPIT1":   PN = "AC18"  !CDS_PN = "AC18";
"ADC2||GPIT2":   PN = "AE19"  !CDS_PN = "AE19";
"ADC3||GPIT3":   PN = "AD19"  !CDS_PN = "AD19";
"ADC4||GPIT4":   PN = "AC19"  !CDS_PN = "AC19";
"ADC5||GPIT5":   PN = "AB19"  !CDS_PN = "AB19";
"ADC6||GPIT6":   PN = "AB18"  !CDS_PN = "AB18";
"ADC7||GPIT7":   PN = "AE18"  !CDS_PN = "AE18";
"ADC8||GPIU0||SALT9":   PN = "AB16"  !CDS_PN = "AB16";
"ADC9||GPIU1||SALT10":   PN = "AA17"  !CDS_PN = "AA17";
"ADC10||GPIU2||SALT11":   PN = "AB17"  !CDS_PN = "AB17";
"ADC11||GPIU3||SALT12":   PN = "AE16"  !CDS_PN = "AE16";
"ADC12||GPIU4||SALT13":   PN = "AC16"  !CDS_PN = "AC16";
"ADC13||GPIU5||SALT14":   PN = "AA16"  !CDS_PN = "AA16";
"ADC14||GPIU6||SALT15":   PN = "AD16"  !CDS_PN = "AD16";
"ADC15||GPIU7||SALT16":   PN = "AC17"  !CDS_PN = "AC17";
"CHASI#":   PN = "AB21"  !CDS_PN = "AB21";
"CLKIN":   PN = "D10"  !CDS_PN = "D10";
"DACB":   PN = "AD21"  !CDS_PN = "AD21";
"DACG":   PN = "AE21"  !CDS_PN = "AE21";
"DACR":   PN = "AF21"  !CDS_PN = "AF21";
"DDCCLK":   PN = "B8"  !CDS_PN = "B8";
"DDCDAT":   PN = "A8"  !CDS_PN = "A8";
"ENTEST":   PN = "C10"  !CDS_PN = "C10";
"EXTRST#":   PN = "B10"  !CDS_PN = "B10";
"GPIOI0||MNTRST2||TXD12":   PN = "D17"  !CDS_PN = "D17";
"GPIOI1||MTDI2||RXD12":   PN = "A16"  !CDS_PN = "A16";
"GPIOI2||MTCK2||TXD13":   PN = "E17"  !CDS_PN = "E17";
"GPIOI3||MTMS2||RXD13":   PN = "D16"  !CDS_PN = "D16";
"GPIOI4||MTDO2":   PN = "C16"  !CDS_PN = "C16";
"GPIOL6||VGAHS":   PN = "B14"  !CDS_PN = "B14";
"GPIOL7||VGAVS":   PN = "C14"  !CDS_PN = "C14";
"GPIOO0||PWM0":   PN = "AD26"  !CDS_PN = "AD26";
"GPIOO1||PWM1":   PN = "AD22"  !CDS_PN = "AD22";
"GPIOO2||PWM2":   PN = "AD23"  !CDS_PN = "AD23";
"GPIOO3||PWM3":   PN = "AD24"  !CDS_PN = "AD24";
"GPIOO4||PWM4":   PN = "AD25"  !CDS_PN = "AD25";
"GPIOO5||PWM5":   PN = "AC22"  !CDS_PN = "AC22";
"GPIOO6||PWM6":   PN = "AC24"  !CDS_PN = "AC24";
"GPIOO7||PWM7":   PN = "AC23"  !CDS_PN = "AC23";
"GPIOP0||PWM8||THRUIN0":   PN = "AB22"  !CDS_PN = "AB22";
"GPIOP1||PWM9||THRUOUT0":   PN = "W24"  !CDS_PN = "W24";
"GPIOP2||PWM10||THRUIN1":   PN = "AA23"  !CDS_PN = "AA23";
"GPIOP3||PWM11||THRUOUT1":   PN = "AA24"  !CDS_PN = "AA24";
"GPIOP4||PWM12||THRUIN2":   PN = "W23"  !CDS_PN = "W23";
"GPIOP5||PWM13||THRUOUT2":   PN = "AB23"  !CDS_PN = "AB23";
"GPIOP6||PWM14":   PN = "AB24"  !CDS_PN = "AB24";
"GPIOP7||PWM15||HBLED#":   PN = "Y23"  !CDS_PN = "Y23";
"GPIOQ0||TACH0":   PN = "AA25"  !CDS_PN = "AA25";
"GPIOQ1||TACH1":   PN = "AB25"  !CDS_PN = "AB25";
"GPIOQ2||TACH2":   PN = "Y24"  !CDS_PN = "Y24";
"GPIOQ3||TACH3":   PN = "AB26"  !CDS_PN = "AB26";
"GPIOQ4||TACH4":   PN = "Y26"  !CDS_PN = "Y26";
"GPIOQ5||TACH5":   PN = "AC26"  !CDS_PN = "AC26";
"GPIOQ6||TACH6":   PN = "Y25"  !CDS_PN = "Y25";
"GPIOQ7||TACH7":   PN = "AA26"  !CDS_PN = "AA26";
"GPIOR0||TACH8":   PN = "V25"  !CDS_PN = "V25";
"GPIOR1||TACH9":   PN = "U24"  !CDS_PN = "U24";
"GPIOR2||TACH10":   PN = "V24"  !CDS_PN = "V24";
"GPIOR3||TACH11":   PN = "V26"  !CDS_PN = "V26";
"GPIOR4||TACH12":   PN = "U25"  !CDS_PN = "U25";
"GPIOR5||TACH13":   PN = "T23"  !CDS_PN = "T23";
"GPIOR6||TACH14":   PN = "W26"  !CDS_PN = "W26";
"GPIOR7||TACH15":   PN = "U26"  !CDS_PN = "U26";
"NTRST||MNTRST1":   PN = "F11"  !CDS_PN = "F11";
"PECI":   PN = "AF16"  !CDS_PN = "AF16";
"PECIVDD":   PN = "AA18"  !CDS_PN = "AA18";
"RSTIND#":   PN = "B7"  !CDS_PN = "B7";
"SRST#":   PN = "E10"  !CDS_PN = "E10";
"SSPRST#":   PN = "D7"  !CDS_PN = "D7";
"TCK||MTCK1":   PN = "B9"  !CDS_PN = "B9";
"TDI||MTDI1":   PN = "D9"  !CDS_PN = "D9";
"TDO||MTDO1":   PN = "C9"  !CDS_PN = "C9";
"TMS||MTMS1":   PN = "A9"  !CDS_PN = "A9";
"USB2A_DN":   PN = "B4"  !CDS_PN = "B4";
"USB2A_DP":   PN = "A4"  !CDS_PN = "A4";
"USB2AV18":   PN = "K10"  !CDS_PN = "K10";
"USB2AV33":   PN = "J10"  !CDS_PN = "J10";
"USB2B_DN":   PN = "B6"  !CDS_PN = "B6";
"USB2B_DP":   PN = "A6"  !CDS_PN = "A6";
BODY = "Q_RES","I351": LOCATION = "R398" #&CDS_LOCATION = "R398" &SEC = "1" #&CDS_SEC = "1";
"A":   PN = "1"  !CDS_PN = "1";
"B":   PN = "2"  !CDS_PN = "2";
BODY = "Q_RES","I353": LOCATION = "R441" #&CDS_LOCATION = "R441" &SEC = "1" #&CDS_SEC = "1";
"A":   PN = "1"  !CDS_PN = "1";
"B":   PN = "2"  !CDS_PN = "2";
BODY = "Q_RES","I354": LOCATION = "R440" #&CDS_LOCATION = "R440" &SEC = "1" #&CDS_SEC = "1";
"A":   PN = "1"  !CDS_PN = "1";
"B":   PN = "2"  !CDS_PN = "2";
BODY = "Q_RES","I367": LOCATION = "R804" #&CDS_LOCATION = "R804" &SEC = "1" #&CDS_SEC = "1";
"A":   PN = "1"  !CDS_PN = "1";
"B":   PN = "2"  !CDS_PN = "2";
BODY = "Q_CAP","I368": #LOCATION = "C40" !CDS_LOCATION = "C40" &SEC = "1" #&CDS_SEC = "1";
"A":   PN = "1"  !CDS_PN = "1";
"B":   PN = "2"  !CDS_PN = "2";
BODY = "Q_CAP","I369": #LOCATION = "C44" !CDS_LOCATION = "C44" &SEC = "1" #&CDS_SEC = "1";
"A":   PN = "1"  !CDS_PN = "1";
"B":   PN = "2"  !CDS_PN = "2";
BODY = "Q_RES","I387": LOCATION = "R853" #&CDS_LOCATION = "R853" &SEC = "1" #&CDS_SEC = "1";
"A":   PN = "1"  !CDS_PN = "1";
"B":   PN = "2"  !CDS_PN = "2";
BODY = "Q_RES","I389": #LOCATION = "R216" !CDS_LOCATION = "R216" &SEC = "1" #&CDS_SEC = "1";
"A":   PN = "1"  !CDS_PN = "1";
"B":   PN = "2"  !CDS_PN = "2";
BODY = "Q_RES","I391": LOCATION = "R462" #&CDS_LOCATION = "R462" &SEC = "1" #&CDS_SEC = "1";
"A":   PN = "1"  !CDS_PN = "1";
"B":   PN = "2"  !CDS_PN = "2";
BODY = "74LVC1G08GW","I393": LOCATION = "U15" #&CDS_LOCATION = "U15" &SEC = "1" #&CDS_SEC = "1";
"A":   PN = "2"  !CDS_PN = "2";
"B":   PN = "1"  !CDS_PN = "1";
"GND":   PN = "3"  !CDS_PN = "3";
"VCC":   PN = "5"  !CDS_PN = "5";
"Y":   PN = "4"  !CDS_PN = "4";
BODY = "Q_CAP","I398": LOCATION = "C26" #&CDS_LOCATION = "C26" &SEC = "1" #&CDS_SEC = "1";
"A":   PN = "1"  !CDS_PN = "1";
"B":   PN = "2"  !CDS_PN = "2";
BODY = "Q_RES","I404": #LOCATION = "R585" !CDS_LOCATION = "R585" &SEC = "1" #&CDS_SEC = "1";
"A":   PN = "1"  !CDS_PN = "1";
"B":   PN = "2"  !CDS_PN = "2";
BODY = "Q_RES","I405": #LOCATION = "R225" !CDS_LOCATION = "R225" &SEC = "1" #&CDS_SEC = "1";
"A":   PN = "1"  !CDS_PN = "1";
"B":   PN = "2"  !CDS_PN = "2";
BODY = "Q_RES","I406": #LOCATION = "R565" !CDS_LOCATION = "R565" &SEC = "1" #&CDS_SEC = "1";
"A":   PN = "1"  !CDS_PN = "1";
"B":   PN = "2"  !CDS_PN = "2";
DRAWING = "@scm_lib.scm(sch_1):page16";
BODY = "Q_CAP","I23": #LOCATION = "C55" !CDS_LOCATION = "C55" &SEC = "1" #&CDS_SEC = "1";
"A":   PN = "1"  !CDS_PN = "1";
"B":   PN = "2"  !CDS_PN = "2";
BODY = "Q_INDUCTOR","I24": #LOCATION = "L10" !CDS_LOCATION = "L10" &SEC = "1" #&CDS_SEC = "1";
"1":   PN = "1"  !CDS_PN = "1";
"2":   PN = "2"  !CDS_PN = "2";
BODY = "Q_INDUCTOR","I29": #LOCATION = "L8" !CDS_LOCATION = "L8" &SEC = "1" #&CDS_SEC = "1";
"1":   PN = "1"  !CDS_PN = "1";
"2":   PN = "2"  !CDS_PN = "2";
BODY = "Q_CAP","I31": #LOCATION = "C52" !CDS_LOCATION = "C52" &SEC = "1" #&CDS_SEC = "1";
"A":   PN = "1"  !CDS_PN = "1";
"B":   PN = "2"  !CDS_PN = "2";
BODY = "Q_CAP","I32": #LOCATION = "C54" !CDS_LOCATION = "C54" &SEC = "1" #&CDS_SEC = "1";
"A":   PN = "1"  !CDS_PN = "1";
"B":   PN = "2"  !CDS_PN = "2";
BODY = "Q_CAP","I33": #LOCATION = "C56" !CDS_LOCATION = "C56" &SEC = "1" #&CDS_SEC = "1";
"A":   PN = "1"  !CDS_PN = "1";
"B":   PN = "2"  !CDS_PN = "2";
BODY = "Q_CAP","I46": #LOCATION = "C63" !CDS_LOCATION = "C63" &SEC = "1" #&CDS_SEC = "1";
"A":   PN = "1"  !CDS_PN = "1";
"B":   PN = "2"  !CDS_PN = "2";
BODY = "Q_INDUCTOR","I47": #LOCATION = "L11" !CDS_LOCATION = "L11" &SEC = "1" #&CDS_SEC = "1";
"1":   PN = "1"  !CDS_PN = "1";
"2":   PN = "2"  !CDS_PN = "2";
BODY = "Q_CAP","I48": #LOCATION = "C67" !CDS_LOCATION = "C67" &SEC = "1" #&CDS_SEC = "1";
"A":   PN = "1"  !CDS_PN = "1";
"B":   PN = "2"  !CDS_PN = "2";
BODY = "Q_CAP","I49": #LOCATION = "C71" !CDS_LOCATION = "C71" &SEC = "1" #&CDS_SEC = "1";
"A":   PN = "1"  !CDS_PN = "1";
"B":   PN = "2"  !CDS_PN = "2";
BODY = "Q_CAP","I51": #LOCATION = "C73" !CDS_LOCATION = "C73" &SEC = "1" #&CDS_SEC = "1";
"A":   PN = "1"  !CDS_PN = "1";
"B":   PN = "2"  !CDS_PN = "2";
BODY = "Q_CAP","I52": #LOCATION = "C58" !CDS_LOCATION = "C58" &SEC = "1" #&CDS_SEC = "1";
"A":   PN = "1"  !CDS_PN = "1";
"B":   PN = "2"  !CDS_PN = "2";
BODY = "Q_CAP","I53": #LOCATION = "C62" !CDS_LOCATION = "C62" &SEC = "1" #&CDS_SEC = "1";
"A":   PN = "1"  !CDS_PN = "1";
"B":   PN = "2"  !CDS_PN = "2";
BODY = "Q_CAP","I54": #LOCATION = "C66" !CDS_LOCATION = "C66" &SEC = "1" #&CDS_SEC = "1";
"A":   PN = "1"  !CDS_PN = "1";
"B":   PN = "2"  !CDS_PN = "2";
BODY = "Q_CAP","I55": #LOCATION = "C61" !CDS_LOCATION = "C61" &SEC = "1" #&CDS_SEC = "1";
"A":   PN = "1"  !CDS_PN = "1";
"B":   PN = "2"  !CDS_PN = "2";
BODY = "Q_CAP","I57": #LOCATION = "C70" !CDS_LOCATION = "C70" &SEC = "1" #&CDS_SEC = "1";
"A":   PN = "1"  !CDS_PN = "1";
"B":   PN = "2"  !CDS_PN = "2";
BODY = "Q_CAP","I58": #LOCATION = "C72" !CDS_LOCATION = "C72" &SEC = "1" #&CDS_SEC = "1";
"A":   PN = "1"  !CDS_PN = "1";
"B":   PN = "2"  !CDS_PN = "2";
BODY = "Q_CAP","I59": #LOCATION = "C69" !CDS_LOCATION = "C69" &SEC = "1" #&CDS_SEC = "1";
"A":   PN = "1"  !CDS_PN = "1";
"B":   PN = "2"  !CDS_PN = "2";
BODY = "Q_CAP","I66": #LOCATION = "C74" !CDS_LOCATION = "C74" &SEC = "1" #&CDS_SEC = "1";
"A":   PN = "1"  !CDS_PN = "1";
"B":   PN = "2"  !CDS_PN = "2";
BODY = "Q_CAP","I79": #LOCATION = "C59" !CDS_LOCATION = "C59" &SEC = "1" #&CDS_SEC = "1";
"A":   PN = "1"  !CDS_PN = "1";
"B":   PN = "2"  !CDS_PN = "2";
BODY = "Q_CAP","I81": #LOCATION = "C64" !CDS_LOCATION = "C64" &SEC = "1" #&CDS_SEC = "1";
"A":   PN = "1"  !CDS_PN = "1";
"B":   PN = "2"  !CDS_PN = "2";
BODY = "Q_CAP","I82": #LOCATION = "C68" !CDS_LOCATION = "C68" &SEC = "1" #&CDS_SEC = "1";
"A":   PN = "1"  !CDS_PN = "1";
"B":   PN = "2"  !CDS_PN = "2";
BODY = "Q_RES","I86": #LOCATION = "R234" !CDS_LOCATION = "R234" &SEC = "1" #&CDS_SEC = "1";
"A":   PN = "1"  !CDS_PN = "1";
"B":   PN = "2"  !CDS_PN = "2";
BODY = "Q_RES","I87": #LOCATION = "R233" !CDS_LOCATION = "R233" &SEC = "1" #&CDS_SEC = "1";
"A":   PN = "1"  !CDS_PN = "1";
"B":   PN = "2"  !CDS_PN = "2";
BODY = "Q_CAP","I93": #LOCATION = "C75" !CDS_LOCATION = "C75" &SEC = "1" #&CDS_SEC = "1";
"A":   PN = "1"  !CDS_PN = "1";
"B":   PN = "2"  !CDS_PN = "2";
BODY = "Q_INDUCTOR","I99": #LOCATION = "L12" !CDS_LOCATION = "L12" &SEC = "1" #&CDS_SEC = "1";
"1":   PN = "1"  !CDS_PN = "1";
"2":   PN = "2"  !CDS_PN = "2";
BODY = "Q_CAP","I100": #LOCATION = "C77" !CDS_LOCATION = "C77" &SEC = "1" #&CDS_SEC = "1";
"A":   PN = "1"  !CDS_PN = "1";
"B":   PN = "2"  !CDS_PN = "2";
BODY = "Q_CAP","I106": #LOCATION = "C83" !CDS_LOCATION = "C83" &SEC = "1" #&CDS_SEC = "1";
"A":   PN = "1"  !CDS_PN = "1";
"B":   PN = "2"  !CDS_PN = "2";
BODY = "Q_CAP","I118": LOCATION = "C89" #&CDS_LOCATION = "C89" &SEC = "1" #&CDS_SEC = "1";
"A":   PN = "1"  !CDS_PN = "1";
"B":   PN = "2"  !CDS_PN = "2";
BODY = "Q_CAP","I119": #LOCATION = "C95" !CDS_LOCATION = "C95" &SEC = "1" #&CDS_SEC = "1";
"A":   PN = "1"  !CDS_PN = "1";
"B":   PN = "2"  !CDS_PN = "2";
BODY = "Q_CAP","I120": #LOCATION = "C85" !CDS_LOCATION = "C85" &SEC = "1" #&CDS_SEC = "1";
"A":   PN = "1"  !CDS_PN = "1";
"B":   PN = "2"  !CDS_PN = "2";
BODY = "Q_CAP","I123": #LOCATION = "C88" !CDS_LOCATION = "C88" &SEC = "1" #&CDS_SEC = "1";
"A":   PN = "1"  !CDS_PN = "1";
"B":   PN = "2"  !CDS_PN = "2";
BODY = "Q_CAP","I124": #LOCATION = "C94" !CDS_LOCATION = "C94" &SEC = "1" #&CDS_SEC = "1";
"A":   PN = "1"  !CDS_PN = "1";
"B":   PN = "2"  !CDS_PN = "2";
BODY = "Q_CAP","I126": #LOCATION = "C102" !CDS_LOCATION = "C102" &SEC = "1" #&CDS_SEC = "1";
"A":   PN = "1"  !CDS_PN = "1";
"B":   PN = "2"  !CDS_PN = "2";
BODY = "Q_CAP","I127": #LOCATION = "C106" !CDS_LOCATION = "C106" &SEC = "1" #&CDS_SEC = "1";
"A":   PN = "1"  !CDS_PN = "1";
"B":   PN = "2"  !CDS_PN = "2";
BODY = "Q_CAP","I128": #LOCATION = "C111" !CDS_LOCATION = "C111" &SEC = "1" #&CDS_SEC = "1";
"A":   PN = "1"  !CDS_PN = "1";
"B":   PN = "2"  !CDS_PN = "2";
BODY = "Q_CAP","I129": #LOCATION = "C116" !CDS_LOCATION = "C116" &SEC = "1" #&CDS_SEC = "1";
"A":   PN = "1"  !CDS_PN = "1";
"B":   PN = "2"  !CDS_PN = "2";
BODY = "Q_CAP","I131": #LOCATION = "C121" !CDS_LOCATION = "C121" &SEC = "1" #&CDS_SEC = "1";
"A":   PN = "1"  !CDS_PN = "1";
"B":   PN = "2"  !CDS_PN = "2";
BODY = "Q_CAP","I132": #LOCATION = "C101" !CDS_LOCATION = "C101" &SEC = "1" #&CDS_SEC = "1";
"A":   PN = "1"  !CDS_PN = "1";
"B":   PN = "2"  !CDS_PN = "2";
BODY = "Q_CAP","I133": #LOCATION = "C110" !CDS_LOCATION = "C110" &SEC = "1" #&CDS_SEC = "1";
"A":   PN = "1"  !CDS_PN = "1";
"B":   PN = "2"  !CDS_PN = "2";
BODY = "Q_CAP","I135": #LOCATION = "C115" !CDS_LOCATION = "C115" &SEC = "1" #&CDS_SEC = "1";
"A":   PN = "1"  !CDS_PN = "1";
"B":   PN = "2"  !CDS_PN = "2";
BODY = "Q_CAP","I143": #LOCATION = "C126" !CDS_LOCATION = "C126" &SEC = "1" #&CDS_SEC = "1";
"A":   PN = "1"  !CDS_PN = "1";
"B":   PN = "2"  !CDS_PN = "2";
BODY = "Q_CAP","I147": #LOCATION = "C87" !CDS_LOCATION = "C87" &SEC = "1" #&CDS_SEC = "1";
"A":   PN = "1"  !CDS_PN = "1";
"B":   PN = "2"  !CDS_PN = "2";
BODY = "Q_CAP","I148": #LOCATION = "C93" !CDS_LOCATION = "C93" &SEC = "1" #&CDS_SEC = "1";
"A":   PN = "1"  !CDS_PN = "1";
"B":   PN = "2"  !CDS_PN = "2";
BODY = "Q_CAP","I149": #LOCATION = "C86" !CDS_LOCATION = "C86" &SEC = "1" #&CDS_SEC = "1";
"A":   PN = "1"  !CDS_PN = "1";
"B":   PN = "2"  !CDS_PN = "2";
BODY = "Q_CAP","I150": #LOCATION = "C92" !CDS_LOCATION = "C92" &SEC = "1" #&CDS_SEC = "1";
"A":   PN = "1"  !CDS_PN = "1";
"B":   PN = "2"  !CDS_PN = "2";
BODY = "Q_CAP","I151": #LOCATION = "C91" !CDS_LOCATION = "C91" &SEC = "1" #&CDS_SEC = "1";
"A":   PN = "1"  !CDS_PN = "1";
"B":   PN = "2"  !CDS_PN = "2";
BODY = "Q_CAP","I152": #LOCATION = "C100" !CDS_LOCATION = "C100" &SEC = "1" #&CDS_SEC = "1";
"A":   PN = "1"  !CDS_PN = "1";
"B":   PN = "2"  !CDS_PN = "2";
BODY = "Q_CAP","I153": #LOCATION = "C105" !CDS_LOCATION = "C105" &SEC = "1" #&CDS_SEC = "1";
"A":   PN = "1"  !CDS_PN = "1";
"B":   PN = "2"  !CDS_PN = "2";
BODY = "Q_CAP","I154": #LOCATION = "C99" !CDS_LOCATION = "C99" &SEC = "1" #&CDS_SEC = "1";
"A":   PN = "1"  !CDS_PN = "1";
"B":   PN = "2"  !CDS_PN = "2";
BODY = "Q_CAP","I155": #LOCATION = "C104" !CDS_LOCATION = "C104" &SEC = "1" #&CDS_SEC = "1";
"A":   PN = "1"  !CDS_PN = "1";
"B":   PN = "2"  !CDS_PN = "2";
BODY = "Q_CAP","I156": #LOCATION = "C109" !CDS_LOCATION = "C109" &SEC = "1" #&CDS_SEC = "1";
"A":   PN = "1"  !CDS_PN = "1";
"B":   PN = "2"  !CDS_PN = "2";
BODY = "Q_CAP","I157": #LOCATION = "C108" !CDS_LOCATION = "C108" &SEC = "1" #&CDS_SEC = "1";
"A":   PN = "1"  !CDS_PN = "1";
"B":   PN = "2"  !CDS_PN = "2";
BODY = "Q_CAP","I158": #LOCATION = "C114" !CDS_LOCATION = "C114" &SEC = "1" #&CDS_SEC = "1";
"A":   PN = "1"  !CDS_PN = "1";
"B":   PN = "2"  !CDS_PN = "2";
BODY = "Q_CAP","I159": #LOCATION = "C119" !CDS_LOCATION = "C119" &SEC = "1" #&CDS_SEC = "1";
"A":   PN = "1"  !CDS_PN = "1";
"B":   PN = "2"  !CDS_PN = "2";
BODY = "Q_CAP","I162": #LOCATION = "C118" !CDS_LOCATION = "C118" &SEC = "1" #&CDS_SEC = "1";
"A":   PN = "1"  !CDS_PN = "1";
"B":   PN = "2"  !CDS_PN = "2";
BODY = "Q_CAP","I163": #LOCATION = "C98" !CDS_LOCATION = "C98" &SEC = "1" #&CDS_SEC = "1";
"A":   PN = "1"  !CDS_PN = "1";
"B":   PN = "2"  !CDS_PN = "2";
BODY = "Q_CAP","I164": #LOCATION = "C103" !CDS_LOCATION = "C103" &SEC = "1" #&CDS_SEC = "1";
"A":   PN = "1"  !CDS_PN = "1";
"B":   PN = "2"  !CDS_PN = "2";
BODY = "Q_CAP","I165": #LOCATION = "C107" !CDS_LOCATION = "C107" &SEC = "1" #&CDS_SEC = "1";
"A":   PN = "1"  !CDS_PN = "1";
"B":   PN = "2"  !CDS_PN = "2";
BODY = "Q_CAP","I166": #LOCATION = "C112" !CDS_LOCATION = "C112" &SEC = "1" #&CDS_SEC = "1";
"A":   PN = "1"  !CDS_PN = "1";
"B":   PN = "2"  !CDS_PN = "2";
BODY = "Q_CAP","I167": #LOCATION = "C117" !CDS_LOCATION = "C117" &SEC = "1" #&CDS_SEC = "1";
"A":   PN = "1"  !CDS_PN = "1";
"B":   PN = "2"  !CDS_PN = "2";
BODY = "Q_CAP","I168": #LOCATION = "C122" !CDS_LOCATION = "C122" &SEC = "1" #&CDS_SEC = "1";
"A":   PN = "1"  !CDS_PN = "1";
"B":   PN = "2"  !CDS_PN = "2";
BODY = "Q_CAP","I169": #LOCATION = "C124" !CDS_LOCATION = "C124" &SEC = "1" #&CDS_SEC = "1";
"A":   PN = "1"  !CDS_PN = "1";
"B":   PN = "2"  !CDS_PN = "2";
BODY = "Q_CAP","I171": #LOCATION = "C123" !CDS_LOCATION = "C123" &SEC = "1" #&CDS_SEC = "1";
"A":   PN = "1"  !CDS_PN = "1";
"B":   PN = "2"  !CDS_PN = "2";
BODY = "Q_CAP","I173": #LOCATION = "C127" !CDS_LOCATION = "C127" &SEC = "1" #&CDS_SEC = "1";
"A":   PN = "1"  !CDS_PN = "1";
"B":   PN = "2"  !CDS_PN = "2";
BODY = "Q_CAP","I174": #LOCATION = "C129" !CDS_LOCATION = "C129" &SEC = "1" #&CDS_SEC = "1";
"A":   PN = "1"  !CDS_PN = "1";
"B":   PN = "2"  !CDS_PN = "2";
BODY = "Q_CAP","I179": #LOCATION = "C84" !CDS_LOCATION = "C84" &SEC = "1" #&CDS_SEC = "1";
"A":   PN = "1"  !CDS_PN = "1";
"B":   PN = "2"  !CDS_PN = "2";
BODY = "Q_CAP","I180": #LOCATION = "C82" !CDS_LOCATION = "C82" &SEC = "1" #&CDS_SEC = "1";
"A":   PN = "1"  !CDS_PN = "1";
"B":   PN = "2"  !CDS_PN = "2";
BODY = "Q_CAP","I183": #LOCATION = "C76" !CDS_LOCATION = "C76" &SEC = "1" #&CDS_SEC = "1";
"A":   PN = "1"  !CDS_PN = "1";
"B":   PN = "2"  !CDS_PN = "2";
BODY = "Q_RES","I187": #LOCATION = "R235" !CDS_LOCATION = "R235" &SEC = "1" #&CDS_SEC = "1";
"A":   PN = "1"  !CDS_PN = "1";
"B":   PN = "2"  !CDS_PN = "2";
BODY = "AST2600A3GP","I188": #LOCATION = "U5" !CDS_LOCATION = "U5" &SEC = "5" #&CDS_SEC = "5";
"ADCAV33_AA21":   PN = "AA21"  !CDS_PN = "AA21";
"ADCAV33_Y21":   PN = "Y21"  !CDS_PN = "Y21";
"ADCREXT0":   PN = "AF20"  !CDS_PN = "AF20";
"ADCREXT1":   PN = "AF18"  !CDS_PN = "AF18";
"ADCVREFEXT0":   PN = "AF19"  !CDS_PN = "AF19";
"ADCVREFEXT1":   PN = "AF17"  !CDS_PN = "AF17";
"ADCVREFN0":   PN = "AB20"  !CDS_PN = "AB20";
"ADCVREFN1":   PN = "AD18"  !CDS_PN = "AD18";
"ADCVREFP0":   PN = "AC20"  !CDS_PN = "AC20";
"ADCVREFP1":   PN = "AD17"  !CDS_PN = "AD17";
"AVDDPLL":   PN = "N5"  !CDS_PN = "N5";
"BATVDD":   PN = "V23"  !CDS_PN = "V23";
"DACAV33_V21":   PN = "V21"  !CDS_PN = "V21";
"DACAV33_W21":   PN = "W21"  !CDS_PN = "W21";
"DACRSET":   PN = "AC21"  !CDS_PN = "AC21";
"DP_VCC10A":   PN = "T8"  !CDS_PN = "T8";
"DP_VCC18A":   PN = "V8"  !CDS_PN = "V8";
"DPLLAVDD":   PN = "J9"  !CDS_PN = "J9";
"I3CVDDH_F19":   PN = "F19"  !CDS_PN = "F19";
"I3CVDDH_F20":   PN = "F20"  !CDS_PN = "F20";
"I3CVDDL1":   PN = "V22"  !CDS_PN = "V22";
"I3CVDDL2":   PN = "U21"  !CDS_PN = "U21";
"IV10D_L9":   PN = "L9"  !CDS_PN = "L9";
"IV10D_L10":   PN = "L10"  !CDS_PN = "L10";
"IV10D_M8":   PN = "M8"  !CDS_PN = "M8";
"IV10D_M11":   PN = "M11"  !CDS_PN = "M11";
"IV10D_N8":   PN = "N8"  !CDS_PN = "N8";
"IV10D_N11":   PN = "N11"  !CDS_PN = "N11";
"IV10D_P8":   PN = "P8"  !CDS_PN = "P8";
"IV10D_P11":   PN = "P11"  !CDS_PN = "P11";
"IV10D_R9":   PN = "R9"  !CDS_PN = "R9";
"IV10D_R10":   PN = "R10"  !CDS_PN = "R10";
"IV12D_K16":   PN = "K16"  !CDS_PN = "K16";
"IV12D_K17":   PN = "K17"  !CDS_PN = "K17";
"IV12D_K18":   PN = "K18"  !CDS_PN = "K18";
"IV12D_K19":   PN = "K19"  !CDS_PN = "K19";
"IV12D_L14":   PN = "L14"  !CDS_PN = "L14";
"IV12D_L21":   PN = "L21"  !CDS_PN = "L21";
"IV12D_M14":   PN = "M14"  !CDS_PN = "M14";
"IV12D_M21":   PN = "M21"  !CDS_PN = "M21";
"IV12D_N14":   PN = "N14"  !CDS_PN = "N14";
"IV12D_N21":   PN = "N21"  !CDS_PN = "N21";
"IV12D_P14":   PN = "P14"  !CDS_PN = "P14";
"IV12D_P21":   PN = "P21"  !CDS_PN = "P21";
"IV12D_R14":   PN = "R14"  !CDS_PN = "R14";
"IV12D_R21":   PN = "R21"  !CDS_PN = "R21";
"IV12D_T14":   PN = "T14"  !CDS_PN = "T14";
"IV12D_T21":   PN = "T21"  !CDS_PN = "T21";
"IV12D_U15":   PN = "U15"  !CDS_PN = "U15";
"IV12D_U16":   PN = "U16"  !CDS_PN = "U16";
"IV12D_U17":   PN = "U17"  !CDS_PN = "U17";
"IV12D_U18":   PN = "U18"  !CDS_PN = "U18";
"LPVDD":   PN = "W15"  !CDS_PN = "W15";
"MVDD_CK":   PN = "M6"  !CDS_PN = "M6";
"MVDD_G6":   PN = "G6"  !CDS_PN = "G6";
"MVDD_H6":   PN = "H6"  !CDS_PN = "H6";
"MVDD_J6":   PN = "J6"  !CDS_PN = "J6";
"MVDD_K6":   PN = "K6"  !CDS_PN = "K6";
"MVDD_L6":   PN = "L6"  !CDS_PN = "L6";
"MVDD_P6":   PN = "P6"  !CDS_PN = "P6";
"MVDD_R6":   PN = "R6"  !CDS_PN = "R6";
"MVDD_T6":   PN = "T6"  !CDS_PN = "T6";
"PE_VCC10A":   PN = "T10"  !CDS_PN = "T10";
"PE_VCC18A":   PN = "V10"  !CDS_PN = "V10";
"PLLAHVDD":   PN = "H14"  !CDS_PN = "H14";
"PLLAVDD_E7":   PN = "E7"  !CDS_PN = "E7";
"PLLAVDD_F7":   PN = "F7"  !CDS_PN = "F7";
"PLLDVDD_E9":   PN = "E9"  !CDS_PN = "E9";
"PLLDVDD_F9":   PN = "F9"  !CDS_PN = "F9";
"PV18D_H8":   PN = "H8"  !CDS_PN = "H8";
"PV18D_J8":   PN = "J8"  !CDS_PN = "J8";
"PV18D_N12":   PN = "N12"  !CDS_PN = "N12";
"PV18D_P12":   PN = "P12"  !CDS_PN = "P12";
"PV18D_R12":   PN = "R12"  !CDS_PN = "R12";
"PV18D_RGM_H12":   PN = "H12"  !CDS_PN = "H12";
"PV18D_RGM_J12":   PN = "J12"  !CDS_PN = "J12";
"PV18D_SLI_L13":   PN = "L13"  !CDS_PN = "L13";
"PV18D_SLI_M13":   PN = "M13"  !CDS_PN = "M13";
"PV18D_SLI_N13":   PN = "N13"  !CDS_PN = "N13";
"PV18D_SLI_P13":   PN = "P13"  !CDS_PN = "P13";
"PV18D_SLI_R13":   PN = "R13"  !CDS_PN = "R13";
"PV18D_SLI_T13":   PN = "T13"  !CDS_PN = "T13";
"PV18D_SLI_U13":   PN = "U13"  !CDS_PN = "U13";
"PV18D_SLI_V13":   PN = "V13"  !CDS_PN = "V13";
"PV18D_SLI_W13":   PN = "W13"  !CDS_PN = "W13";
"PV18D_SLI_W14":   PN = "W14"  !CDS_PN = "W14";
"PV18D_U6":   PN = "U6"  !CDS_PN = "U6";
"PV18D_V6":   PN = "V6"  !CDS_PN = "V6";
"PV33D_H15":   PN = "H15"  !CDS_PN = "H15";
"PV33D_H16":   PN = "H16"  !CDS_PN = "H16";
"PV33D_H17":   PN = "H17"  !CDS_PN = "H17";
"PV33D_N22":   PN = "N22"  !CDS_PN = "N22";
"PV33D_P22":   PN = "P22"  !CDS_PN = "P22";
"PV33D_R22":   PN = "R22"  !CDS_PN = "R22";
"PV33D_RGM_K11":   PN = "K11"  !CDS_PN = "K11";
"PV33D_RGM_K12":   PN = "K12"  !CDS_PN = "K12";
"PV33D_T22":   PN = "T22"  !CDS_PN = "T22";
"PV33D_W16":   PN = "W16"  !CDS_PN = "W16";
"PV33D_W17":   PN = "W17"  !CDS_PN = "W17";
"PV33D_W18":   PN = "W18"  !CDS_PN = "W18";
"PV33D_W19":   PN = "W19"  !CDS_PN = "W19";
"RC_VCC10A":   PN = "T9"  !CDS_PN = "T9";
"RC_VCC18A":   PN = "V9"  !CDS_PN = "V9";
"RVDD_J21":   PN = "J21"  !CDS_PN = "J21";
"RVDD_K21":   PN = "K21"  !CDS_PN = "K21";
"RVDD_L22":   PN = "L22"  !CDS_PN = "L22";
"RVDD_M22":   PN = "M22"  !CDS_PN = "M22";
"SD1VDD_G21":   PN = "G21"  !CDS_PN = "G21";
"SD1VDD_H21":   PN = "H21"  !CDS_PN = "H21";
"SD2VDD_H18":   PN = "H18"  !CDS_PN = "H18";
"SD2VDD_H19":   PN = "H19"  !CDS_PN = "H19";
BODY = "Q_CAP","I189": #LOCATION = "C113" !CDS_LOCATION = "C113" &SEC = "1" #&CDS_SEC = "1";
"A":   PN = "1"  !CDS_PN = "1";
"B":   PN = "2"  !CDS_PN = "2";
BODY = "Q_CAP","I190": #LOCATION = "C120" !CDS_LOCATION = "C120" &SEC = "1" #&CDS_SEC = "1";
"A":   PN = "1"  !CDS_PN = "1";
"B":   PN = "2"  !CDS_PN = "2";
BODY = "Q_CAP","I191": #LOCATION = "C125" !CDS_LOCATION = "C125" &SEC = "1" #&CDS_SEC = "1";
"A":   PN = "1"  !CDS_PN = "1";
"B":   PN = "2"  !CDS_PN = "2";
BODY = "Q_CAP","I192": #LOCATION = "C131" !CDS_LOCATION = "C131" &SEC = "1" #&CDS_SEC = "1";
"A":   PN = "1"  !CDS_PN = "1";
"B":   PN = "2"  !CDS_PN = "2";
BODY = "Q_CAP","I193": #LOCATION = "C132" !CDS_LOCATION = "C132" &SEC = "1" #&CDS_SEC = "1";
"A":   PN = "1"  !CDS_PN = "1";
"B":   PN = "2"  !CDS_PN = "2";
DRAWING = "@scm_lib.scm(sch_1):page17";
BODY = "Q_RES","I92": #LOCATION = "R281" !CDS_LOCATION = "R281" &SEC = "1" #&CDS_SEC = "1";
"A":   PN = "1"  !CDS_PN = "1";
"B":   PN = "2"  !CDS_PN = "2";
BODY = "Q_RES","I94": #LOCATION = "R280" !CDS_LOCATION = "R280" &SEC = "1" #&CDS_SEC = "1";
"A":   PN = "1"  !CDS_PN = "1";
"B":   PN = "2"  !CDS_PN = "2";
BODY = "Q_RES","I95": #LOCATION = "R279" !CDS_LOCATION = "R279" &SEC = "1" #&CDS_SEC = "1";
"A":   PN = "1"  !CDS_PN = "1";
"B":   PN = "2"  !CDS_PN = "2";
BODY = "Q_CAP","I97": #LOCATION = "C140" !CDS_LOCATION = "C140" &SEC = "1" #&CDS_SEC = "1";
"A":   PN = "1"  !CDS_PN = "1";
"B":   PN = "2"  !CDS_PN = "2";
BODY = "Q_CAP","I98": #LOCATION = "C139" !CDS_LOCATION = "C139" &SEC = "1" #&CDS_SEC = "1";
"A":   PN = "1"  !CDS_PN = "1";
"B":   PN = "2"  !CDS_PN = "2";
BODY = "Q_RES","I101": #LOCATION = "R278" !CDS_LOCATION = "R278" &SEC = "1" #&CDS_SEC = "1";
"A":   PN = "1"  !CDS_PN = "1";
"B":   PN = "2"  !CDS_PN = "2";
BODY = "Q_CAP","I104": #LOCATION = "C133" !CDS_LOCATION = "C133" &SEC = "1" #&CDS_SEC = "1";
"A":   PN = "1"  !CDS_PN = "1";
"B":   PN = "2"  !CDS_PN = "2";
BODY = "Q_CAP","I106": #LOCATION = "C134" !CDS_LOCATION = "C134" &SEC = "1" #&CDS_SEC = "1";
"A":   PN = "1"  !CDS_PN = "1";
"B":   PN = "2"  !CDS_PN = "2";
BODY = "Q_CAP","I107": #LOCATION = "C135" !CDS_LOCATION = "C135" &SEC = "1" #&CDS_SEC = "1";
"A":   PN = "1"  !CDS_PN = "1";
"B":   PN = "2"  !CDS_PN = "2";
BODY = "Q_CAP","I108": #LOCATION = "C137" !CDS_LOCATION = "C137" &SEC = "1" #&CDS_SEC = "1";
"A":   PN = "1"  !CDS_PN = "1";
"B":   PN = "2"  !CDS_PN = "2";
BODY = "Q_CAP","I109": #LOCATION = "C138" !CDS_LOCATION = "C138" &SEC = "1" #&CDS_SEC = "1";
"A":   PN = "1"  !CDS_PN = "1";
"B":   PN = "2"  !CDS_PN = "2";
BODY = "Q_CAP","I110": #LOCATION = "C136" !CDS_LOCATION = "C136" &SEC = "1" #&CDS_SEC = "1";
"A":   PN = "1"  !CDS_PN = "1";
"B":   PN = "2"  !CDS_PN = "2";
BODY = "Q_CAP","I118": #LOCATION = "C49" !CDS_LOCATION = "C49" &SEC = "1" #&CDS_SEC = "1";
"A":   PN = "1"  !CDS_PN = "1";
"B":   PN = "2"  !CDS_PN = "2";
BODY = "Q_INDUCTOR","I120": #LOCATION = "L5" !CDS_LOCATION = "L5" &SEC = "1" #&CDS_SEC = "1";
"1":   PN = "1"  !CDS_PN = "1";
"2":   PN = "2"  !CDS_PN = "2";
BODY = "Q_CAP","I122": #LOCATION = "C46" !CDS_LOCATION = "C46" &SEC = "1" #&CDS_SEC = "1";
"A":   PN = "1"  !CDS_PN = "1";
"B":   PN = "2"  !CDS_PN = "2";
BODY = "Q_INDUCTOR","I124": #LOCATION = "L6" !CDS_LOCATION = "L6" &SEC = "1" #&CDS_SEC = "1";
"1":   PN = "1"  !CDS_PN = "1";
"2":   PN = "2"  !CDS_PN = "2";
BODY = "Q_CAP","I126": #LOCATION = "C50" !CDS_LOCATION = "C50" &SEC = "1" #&CDS_SEC = "1";
"A":   PN = "1"  !CDS_PN = "1";
"B":   PN = "2"  !CDS_PN = "2";
BODY = "Q_CAP","I128": #LOCATION = "C47" !CDS_LOCATION = "C47" &SEC = "1" #&CDS_SEC = "1";
"A":   PN = "1"  !CDS_PN = "1";
"B":   PN = "2"  !CDS_PN = "2";
BODY = "Q_RES","I131": #LOCATION = "R231" !CDS_LOCATION = "R231" &SEC = "1" #&CDS_SEC = "1";
"A":   PN = "1"  !CDS_PN = "1";
"B":   PN = "2"  !CDS_PN = "2";
BODY = "Q_CAP","I133": #LOCATION = "C57" !CDS_LOCATION = "C57" &SEC = "1" #&CDS_SEC = "1";
"A":   PN = "1"  !CDS_PN = "1";
"B":   PN = "2"  !CDS_PN = "2";
BODY = "Q_CAP","I135": #LOCATION = "C53" !CDS_LOCATION = "C53" &SEC = "1" #&CDS_SEC = "1";
"A":   PN = "1"  !CDS_PN = "1";
"B":   PN = "2"  !CDS_PN = "2";
BODY = "Q_RES","I136": #LOCATION = "R232" !CDS_LOCATION = "R232" &SEC = "1" #&CDS_SEC = "1";
"A":   PN = "1"  !CDS_PN = "1";
"B":   PN = "2"  !CDS_PN = "2";
BODY = "Q_CAP","I139": #LOCATION = "C65" !CDS_LOCATION = "C65" &SEC = "1" #&CDS_SEC = "1";
"A":   PN = "1"  !CDS_PN = "1";
"B":   PN = "2"  !CDS_PN = "2";
BODY = "Q_CAP","I141": #LOCATION = "C60" !CDS_LOCATION = "C60" &SEC = "1" #&CDS_SEC = "1";
"A":   PN = "1"  !CDS_PN = "1";
"B":   PN = "2"  !CDS_PN = "2";
BODY = "Q_INDUCTOR","I142": #LOCATION = "L9" !CDS_LOCATION = "L9" &SEC = "1" #&CDS_SEC = "1";
"1":   PN = "1"  !CDS_PN = "1";
"2":   PN = "2"  !CDS_PN = "2";
BODY = "Q_CAP","I145": #LOCATION = "C51" !CDS_LOCATION = "C51" &SEC = "1" #&CDS_SEC = "1";
"A":   PN = "1"  !CDS_PN = "1";
"B":   PN = "2"  !CDS_PN = "2";
BODY = "Q_INDUCTOR","I146": #LOCATION = "L7" !CDS_LOCATION = "L7" &SEC = "1" #&CDS_SEC = "1";
"1":   PN = "1"  !CDS_PN = "1";
"2":   PN = "2"  !CDS_PN = "2";
BODY = "Q_CAP","I148": #LOCATION = "C48" !CDS_LOCATION = "C48" &SEC = "1" #&CDS_SEC = "1";
"A":   PN = "1"  !CDS_PN = "1";
"B":   PN = "2"  !CDS_PN = "2";
BODY = "Q_CAP","I151": #LOCATION = "C81" !CDS_LOCATION = "C81" &SEC = "1" #&CDS_SEC = "1";
"A":   PN = "1"  !CDS_PN = "1";
"B":   PN = "2"  !CDS_PN = "2";
BODY = "Q_CAP","I153": #LOCATION = "C80" !CDS_LOCATION = "C80" &SEC = "1" #&CDS_SEC = "1";
"A":   PN = "1"  !CDS_PN = "1";
"B":   PN = "2"  !CDS_PN = "2";
BODY = "Q_INDUCTOR","I154": #LOCATION = "L14" !CDS_LOCATION = "L14" &SEC = "1" #&CDS_SEC = "1";
"1":   PN = "1"  !CDS_PN = "1";
"2":   PN = "2"  !CDS_PN = "2";
BODY = "Q_CAP","I157": #LOCATION = "C79" !CDS_LOCATION = "C79" &SEC = "1" #&CDS_SEC = "1";
"A":   PN = "1"  !CDS_PN = "1";
"B":   PN = "2"  !CDS_PN = "2";
BODY = "Q_INDUCTOR","I158": #LOCATION = "L13" !CDS_LOCATION = "L13" &SEC = "1" #&CDS_SEC = "1";
"1":   PN = "1"  !CDS_PN = "1";
"2":   PN = "2"  !CDS_PN = "2";
BODY = "Q_CAP","I160": #LOCATION = "C78" !CDS_LOCATION = "C78" &SEC = "1" #&CDS_SEC = "1";
"A":   PN = "1"  !CDS_PN = "1";
"B":   PN = "2"  !CDS_PN = "2";
BODY = "Q_CAP","I163": #LOCATION = "C130" !CDS_LOCATION = "C130" &SEC = "1" #&CDS_SEC = "1";
"A":   PN = "1"  !CDS_PN = "1";
"B":   PN = "2"  !CDS_PN = "2";
BODY = "Q_CAP","I165": #LOCATION = "C128" !CDS_LOCATION = "C128" &SEC = "1" #&CDS_SEC = "1";
"A":   PN = "1"  !CDS_PN = "1";
"B":   PN = "2"  !CDS_PN = "2";
BODY = "Q_INDUCTOR","I166": #LOCATION = "L16" !CDS_LOCATION = "L16" &SEC = "1" #&CDS_SEC = "1";
"1":   PN = "1"  !CDS_PN = "1";
"2":   PN = "2"  !CDS_PN = "2";
BODY = "Q_CAP","I169": #LOCATION = "C97" !CDS_LOCATION = "C97" &SEC = "1" #&CDS_SEC = "1";
"A":   PN = "1"  !CDS_PN = "1";
"B":   PN = "2"  !CDS_PN = "2";
BODY = "Q_INDUCTOR","I170": #LOCATION = "L15" !CDS_LOCATION = "L15" &SEC = "1" #&CDS_SEC = "1";
"1":   PN = "1"  !CDS_PN = "1";
"2":   PN = "2"  !CDS_PN = "2";
BODY = "Q_CAP","I173": #LOCATION = "C90" !CDS_LOCATION = "C90" &SEC = "1" #&CDS_SEC = "1";
"A":   PN = "1"  !CDS_PN = "1";
"B":   PN = "2"  !CDS_PN = "2";
BODY = "Q_INDUCTOR","I176": #LOCATION = "L17" !CDS_LOCATION = "L17" &SEC = "1" #&CDS_SEC = "1";
"1":   PN = "1"  !CDS_PN = "1";
"2":   PN = "2"  !CDS_PN = "2";
BODY = "Q_CAP","I178": #LOCATION = "C96" !CDS_LOCATION = "C96" &SEC = "1" #&CDS_SEC = "1";
"A":   PN = "1"  !CDS_PN = "1";
"B":   PN = "2"  !CDS_PN = "2";
BODY = "Q_CAP","I180": #LOCATION = "C224" !CDS_LOCATION = "C224" &SEC = "1" #&CDS_SEC = "1";
"A":   PN = "1"  !CDS_PN = "1";
"B":   PN = "2"  !CDS_PN = "2";
BODY = "MOSFET_N_GSD","I227": #LOCATION = "Q10" !CDS_LOCATION = "Q10" #SEC = "1" !CDS_SEC = "1";
"DRAIN":   PN = "D"  !CDS_PN = "D";
"GATE":   PN = "G"  !CDS_PN = "G";
"SOURCE":   PN = "S"  !CDS_PN = "S";
BODY = "Q_RES","I228": #LOCATION = "R713" !CDS_LOCATION = "R713" &SEC = "1" #&CDS_SEC = "1";
"A":   PN = "1"  !CDS_PN = "1";
"B":   PN = "2"  !CDS_PN = "2";
BODY = "Q_RES","I230": #LOCATION = "R716" !CDS_LOCATION = "R716" &SEC = "1" #&CDS_SEC = "1";
"A":   PN = "1"  !CDS_PN = "1";
"B":   PN = "2"  !CDS_PN = "2";
BODY = "Q_CAP","I234": #LOCATION = "C273" !CDS_LOCATION = "C273" &SEC = "1" #&CDS_SEC = "1";
"A":   PN = "1"  !CDS_PN = "1";
"B":   PN = "2"  !CDS_PN = "2";
BODY = "Q_CAP","I239": #LOCATION = "C270" !CDS_LOCATION = "C270" &SEC = "1" #&CDS_SEC = "1";
"A":   PN = "1"  !CDS_PN = "1";
"B":   PN = "2"  !CDS_PN = "2";
BODY = "Q_CAP","I250": #LOCATION = "C284" !CDS_LOCATION = "C284" &SEC = "1" #&CDS_SEC = "1";
"A":   PN = "1"  !CDS_PN = "1";
"B":   PN = "2"  !CDS_PN = "2";
BODY = "Q_CAP","I252": #LOCATION = "C282" !CDS_LOCATION = "C282" &SEC = "1" #&CDS_SEC = "1";
"A":   PN = "1"  !CDS_PN = "1";
"B":   PN = "2"  !CDS_PN = "2";
BODY = "Q_CAP","I253": #LOCATION = "C277" !CDS_LOCATION = "C277" &SEC = "1" #&CDS_SEC = "1";
"A":   PN = "1"  !CDS_PN = "1";
"B":   PN = "2"  !CDS_PN = "2";
BODY = "Q_CAP","I255": #LOCATION = "C279" !CDS_LOCATION = "C279" &SEC = "1" #&CDS_SEC = "1";
"A":   PN = "1"  !CDS_PN = "1";
"B":   PN = "2"  !CDS_PN = "2";
BODY = "Q_RES","I256": #LOCATION = "R780" !CDS_LOCATION = "R780" &SEC = "1" #&CDS_SEC = "1";
"A":   PN = "1"  !CDS_PN = "1";
"B":   PN = "2"  !CDS_PN = "2";
BODY = "Q_RES","I259": #LOCATION = "R779" !CDS_LOCATION = "R779" &SEC = "1" #&CDS_SEC = "1";
"A":   PN = "1"  !CDS_PN = "1";
"B":   PN = "2"  !CDS_PN = "2";
BODY = "Q_RES","I260": #LOCATION = "R783" !CDS_LOCATION = "R783" &SEC = "1" #&CDS_SEC = "1";
"A":   PN = "1"  !CDS_PN = "1";
"B":   PN = "2"  !CDS_PN = "2";
BODY = "Q_RES","I263": #LOCATION = "R781" !CDS_LOCATION = "R781" &SEC = "1" #&CDS_SEC = "1";
"A":   PN = "1"  !CDS_PN = "1";
"B":   PN = "2"  !CDS_PN = "2";
BODY = "Q_RES","I264": #LOCATION = "R782" !CDS_LOCATION = "R782" &SEC = "1" #&CDS_SEC = "1";
"A":   PN = "1"  !CDS_PN = "1";
"B":   PN = "2"  !CDS_PN = "2";
BODY = "Q_RES","I267": #LOCATION = "R784" !CDS_LOCATION = "R784" &SEC = "1" #&CDS_SEC = "1";
"A":   PN = "1"  !CDS_PN = "1";
"B":   PN = "2"  !CDS_PN = "2";
BODY = "Q_INDUCTOR","I272": #LOCATION = "L2" !CDS_LOCATION = "L2" &SEC = "1" #&CDS_SEC = "1";
"1":   PN = "1"  !CDS_PN = "1";
"2":   PN = "2"  !CDS_PN = "2";
BODY = "MOSFET_NCH_4D1S","I274": #LOCATION = "Q5" !CDS_LOCATION = "Q5" #SEC = "1" !CDS_SEC = "1";
"1":   PN = "1"  !CDS_PN = "1";
"2":   PN = "2"  !CDS_PN = "2";
"3":   PN = "3"  !CDS_PN = "3";
"4":   PN = "4"  !CDS_PN = "4";
"5":   PN = "5"  !CDS_PN = "5";
"6":   PN = "6"  !CDS_PN = "6";
BODY = "Q_RES","I278": #LOCATION = "R645" !CDS_LOCATION = "R645" &SEC = "1" #&CDS_SEC = "1";
"A":   PN = "1"  !CDS_PN = "1";
"B":   PN = "2"  !CDS_PN = "2";
BODY = "Q_RES","I279": #LOCATION = "R646" !CDS_LOCATION = "R646" &SEC = "1" #&CDS_SEC = "1";
"A":   PN = "1"  !CDS_PN = "1";
"B":   PN = "2"  !CDS_PN = "2";
BODY = "Q_RES","I284": #LOCATION = "R493" !CDS_LOCATION = "R493" &SEC = "1" #&CDS_SEC = "1";
"A":   PN = "1"  !CDS_PN = "1";
"B":   PN = "2"  !CDS_PN = "2";
BODY = "AST2600A3GP","I286": #LOCATION = "U5" !CDS_LOCATION = "U5" &SEC = "6" #&CDS_SEC = "6";
"GND_A1":   PN = "A1"  !CDS_PN = "A1";
"GND_A5":   PN = "A5"  !CDS_PN = "A5";
"GND_A26":   PN = "A26"  !CDS_PN = "A26";
"GND_AA1":   PN = "AA1"  !CDS_PN = "AA1";
"GND_AA3":   PN = "AA3"  !CDS_PN = "AA3";
"GND_AA6":   PN = "AA6"  !CDS_PN = "AA6";
"GND_AA7":   PN = "AA7"  !CDS_PN = "AA7";
"GND_AA8":   PN = "AA8"  !CDS_PN = "AA8";
"GND_AA10":   PN = "AA10"  !CDS_PN = "AA10";
"GND_AA14":   PN = "AA14"  !CDS_PN = "AA14";
"GND_AA15":   PN = "AA15"  !CDS_PN = "AA15";
"GND_AA19":   PN = "AA19"  !CDS_PN = "AA19";
"GND_AA20":   PN = "AA20"  !CDS_PN = "AA20";
"GND_AA22":   PN = "AA22"  !CDS_PN = "AA22";
"GND_AC2":   PN = "AC2"  !CDS_PN = "AC2";
"GND_AC6":   PN = "AC6"  !CDS_PN = "AC6";
"GND_AC25":   PN = "AC25"  !CDS_PN = "AC25";
"GND_AD1":   PN = "AD1"  !CDS_PN = "AD1";
"GND_AD4":   PN = "AD4"  !CDS_PN = "AD4";
"GND_AE3":   PN = "AE3"  !CDS_PN = "AE3";
"GND_AE6":   PN = "AE6"  !CDS_PN = "AE6";
"GND_AE9":   PN = "AE9"  !CDS_PN = "AE9";
"GND_AE13":   PN = "AE13"  !CDS_PN = "AE13";
"GND_AE17":   PN = "AE17"  !CDS_PN = "AE17";
"GND_AE20":   PN = "AE20"  !CDS_PN = "AE20";
"GND_AE23":   PN = "AE23"  !CDS_PN = "AE23";
"GND_AF1":   PN = "AF1"  !CDS_PN = "AF1";
"GND_AF4":   PN = "AF4"  !CDS_PN = "AF4";
"GND_AF26":   PN = "AF26"  !CDS_PN = "AF26";
"GND_B5":   PN = "B5"  !CDS_PN = "B5";
"GND_B11":   PN = "B11"  !CDS_PN = "B11";
"GND_B15":   PN = "B15"  !CDS_PN = "B15";
"GND_B19":   PN = "B19"  !CDS_PN = "B19";
"GND_B23":   PN = "B23"  !CDS_PN = "B23";
"GND_C3":   PN = "C3"  !CDS_PN = "C3";
"GND_D25":   PN = "D25"  !CDS_PN = "D25";
"GND_E8":   PN = "E8"  !CDS_PN = "E8";
"GND_F6":   PN = "F6"  !CDS_PN = "F6";
"GND_F8":   PN = "F8"  !CDS_PN = "F8";
"GND_F10":   PN = "F10"  !CDS_PN = "F10";
"GND_F12":   PN = "F12"  !CDS_PN = "F12";
"GND_F14":   PN = "F14"  !CDS_PN = "F14";
"GND_F16":   PN = "F16"  !CDS_PN = "F16";
"GND_F17":   PN = "F17"  !CDS_PN = "F17";
"GND_F18":   PN = "F18"  !CDS_PN = "F18";
"GND_F21":   PN = "F21"  !CDS_PN = "F21";
"GND_G2":   PN = "G2"  !CDS_PN = "G2";
"GND_G25":   PN = "G25"  !CDS_PN = "G25";
"GND_H4":   PN = "H4"  !CDS_PN = "H4";
"GND_H9":   PN = "H9"  !CDS_PN = "H9";
"GND_H10":   PN = "H10"  !CDS_PN = "H10";
"GND_H11":   PN = "H11"  !CDS_PN = "H11";
"GND_H13":   PN = "H13"  !CDS_PN = "H13";
"GND_J2":   PN = "J2"  !CDS_PN = "J2";
"GND_J11":   PN = "J11"  !CDS_PN = "J11";
"GND_J13":   PN = "J13"  !CDS_PN = "J13";
"GND_J14":   PN = "J14"  !CDS_PN = "J14";
"GND_J15":   PN = "J15"  !CDS_PN = "J15";
"GND_J16":   PN = "J16"  !CDS_PN = "J16";
"GND_J17":   PN = "J17"  !CDS_PN = "J17";
"GND_J18":   PN = "J18"  !CDS_PN = "J18";
"GND_J19":   PN = "J19"  !CDS_PN = "J19";
"GND_K4":   PN = "K4"  !CDS_PN = "K4";
"GND_K8":   PN = "K8"  !CDS_PN = "K8";
"GND_K9":   PN = "K9"  !CDS_PN = "K9";
"GND_K13":   PN = "K13"  !CDS_PN = "K13";
"GND_K14":   PN = "K14"  !CDS_PN = "K14";
"GND_K15":   PN = "K15"  !CDS_PN = "K15";
"GND_K22":   PN = "K22"  !CDS_PN = "K22";
"GND_L2":   PN = "L2"  !CDS_PN = "L2";
"GND_L8":   PN = "L8"  !CDS_PN = "L8";
"GND_L11":   PN = "L11"  !CDS_PN = "L11";
"GND_L12":   PN = "L12"  !CDS_PN = "L12";
"GND_L15":   PN = "L15"  !CDS_PN = "L15";
"GND_L16":   PN = "L16"  !CDS_PN = "L16";
"GND_L17":   PN = "L17"  !CDS_PN = "L17";
"GND_L18":   PN = "L18"  !CDS_PN = "L18";
"GND_L19":   PN = "L19"  !CDS_PN = "L19";
"GND_L25":   PN = "L25"  !CDS_PN = "L25";
"GND_M4":   PN = "M4"  !CDS_PN = "M4";
"GND_M9":   PN = "M9"  !CDS_PN = "M9";
"GND_M10":   PN = "M10"  !CDS_PN = "M10";
"GND_M12":   PN = "M12"  !CDS_PN = "M12";
"GND_M15":   PN = "M15"  !CDS_PN = "M15";
"GND_M16":   PN = "M16"  !CDS_PN = "M16";
"GND_M17":   PN = "M17"  !CDS_PN = "M17";
"GND_M18":   PN = "M18"  !CDS_PN = "M18";
"GND_M19":   PN = "M19"  !CDS_PN = "M19";
"GND_N2":   PN = "N2"  !CDS_PN = "N2";
"GND_N6":   PN = "N6"  !CDS_PN = "N6";
"GND_N9":   PN = "N9"  !CDS_PN = "N9";
"GND_N10":   PN = "N10"  !CDS_PN = "N10";
"GND_N15":   PN = "N15"  !CDS_PN = "N15";
"GND_N16":   PN = "N16"  !CDS_PN = "N16";
"GND_N17":   PN = "N17"  !CDS_PN = "N17";
"GND_N18":   PN = "N18"  !CDS_PN = "N18";
"GND_N19":   PN = "N19"  !CDS_PN = "N19";
"GND_P4":   PN = "P4"  !CDS_PN = "P4";
"GND_P9":   PN = "P9"  !CDS_PN = "P9";
"GND_P10":   PN = "P10"  !CDS_PN = "P10";
"GND_P15":   PN = "P15"  !CDS_PN = "P15";
"GND_P16":   PN = "P16"  !CDS_PN = "P16";
"GND_P17":   PN = "P17"  !CDS_PN = "P17";
"GND_P18":   PN = "P18"  !CDS_PN = "P18";
"GND_P19":   PN = "P19"  !CDS_PN = "P19";
"GND_R2":   PN = "R2"  !CDS_PN = "R2";
"GND_R8":   PN = "R8"  !CDS_PN = "R8";
"GND_R11":   PN = "R11"  !CDS_PN = "R11";
"GND_R15":   PN = "R15"  !CDS_PN = "R15";
"GND_R16":   PN = "R16"  !CDS_PN = "R16";
"GND_R17":   PN = "R17"  !CDS_PN = "R17";
"GND_R18":   PN = "R18"  !CDS_PN = "R18";
"GND_R19":   PN = "R19"  !CDS_PN = "R19";
"GND_R25":   PN = "R25"  !CDS_PN = "R25";
"GND_T4":   PN = "T4"  !CDS_PN = "T4";
"GND_T11":   PN = "T11"  !CDS_PN = "T11";
"GND_T12":   PN = "T12"  !CDS_PN = "T12";
"GND_T15":   PN = "T15"  !CDS_PN = "T15";
"GND_T16":   PN = "T16"  !CDS_PN = "T16";
"GND_T17":   PN = "T17"  !CDS_PN = "T17";
"GND_T18":   PN = "T18"  !CDS_PN = "T18";
"GND_T19":   PN = "T19"  !CDS_PN = "T19";
"GND_U2":   PN = "U2"  !CDS_PN = "U2";
"GND_U8":   PN = "U8"  !CDS_PN = "U8";
"GND_U9":   PN = "U9"  !CDS_PN = "U9";
"GND_U10":   PN = "U10"  !CDS_PN = "U10";
"GND_U11":   PN = "U11"  !CDS_PN = "U11";
"GND_U12":   PN = "U12"  !CDS_PN = "U12";
"GND_U14":   PN = "U14"  !CDS_PN = "U14";
"GND_U19":   PN = "U19"  !CDS_PN = "U19";
"GND_U22":   PN = "U22"  !CDS_PN = "U22";
"GND_U23":   PN = "U23"  !CDS_PN = "U23";
"GND_V5":   PN = "V5"  !CDS_PN = "V5";
"GND_V11":   PN = "V11"  !CDS_PN = "V11";
"GND_V12":   PN = "V12"  !CDS_PN = "V12";
"GND_V14":   PN = "V14"  !CDS_PN = "V14";
"GND_V15":   PN = "V15"  !CDS_PN = "V15";
"GND_V16":   PN = "V16"  !CDS_PN = "V16";
"GND_V17":   PN = "V17"  !CDS_PN = "V17";
"GND_V18":   PN = "V18"  !CDS_PN = "V18";
"GND_V19":   PN = "V19"  !CDS_PN = "V19";
"GND_W5":   PN = "W5"  !CDS_PN = "W5";
"GND_W6":   PN = "W6"  !CDS_PN = "W6";
"GND_W8":   PN = "W8"  !CDS_PN = "W8";
"GND_W9":   PN = "W9"  !CDS_PN = "W9";
"GND_W10":   PN = "W10"  !CDS_PN = "W10";
"GND_W11":   PN = "W11"  !CDS_PN = "W11";
"GND_W12":   PN = "W12"  !CDS_PN = "W12";
"GND_W22":   PN = "W22"  !CDS_PN = "W22";
"GND_W25":   PN = "W25"  !CDS_PN = "W25";
"GND_Y6":   PN = "Y6"  !CDS_PN = "Y6";
"GND_Y22":   PN = "Y22"  !CDS_PN = "Y22";
BODY = "MOSFET_PCH_GDS","I289": #LOCATION = "Q4" !CDS_LOCATION = "Q4" &SEC = "1" #&CDS_SEC = "1";
"D":   PN = "D"  !CDS_PN = "D";
"G":   PN = "G"  !CDS_PN = "G";
"S":   PN = "S"  !CDS_PN = "S";
DRAWING = "@scm_lib.scm(sch_1):page20";
BODY = "Q_CAP","I4": #LOCATION = "C1" !CDS_LOCATION = "C1" #SEC = "1" !CDS_SEC = "1";
"A":   PN = "1"  !CDS_PN = "1";
"B":   PN = "2"  !CDS_PN = "2";
BODY = "Q_CAP","I5": #LOCATION = "C2" !CDS_LOCATION = "C2" #SEC = "1" !CDS_SEC = "1";
"A":   PN = "1"  !CDS_PN = "1";
"B":   PN = "2"  !CDS_PN = "2";
BODY = "Q_CAP","I6": #LOCATION = "C3" !CDS_LOCATION = "C3" #SEC = "1" !CDS_SEC = "1";
"A":   PN = "1"  !CDS_PN = "1";
"B":   PN = "2"  !CDS_PN = "2";
BODY = "Q_CAP","I7": #LOCATION = "C4" !CDS_LOCATION = "C4" #SEC = "1" !CDS_SEC = "1";
"A":   PN = "1"  !CDS_PN = "1";
"B":   PN = "2"  !CDS_PN = "2";
BODY = "Q_RES","I13": #LOCATION = "R2" !CDS_LOCATION = "R2" #SEC = "1" !CDS_SEC = "1";
"A":   PN = "1"  !CDS_PN = "1";
"B":   PN = "2"  !CDS_PN = "2";
BODY = "Q_RES","I14": #LOCATION = "R1" !CDS_LOCATION = "R1" #SEC = "1" !CDS_SEC = "1";
"A":   PN = "1"  !CDS_PN = "1";
"B":   PN = "2"  !CDS_PN = "2";
BODY = "Q_RES","I17": #LOCATION = "R3" !CDS_LOCATION = "R3" #SEC = "1" !CDS_SEC = "1";
"A":   PN = "1"  !CDS_PN = "1";
"B":   PN = "2"  !CDS_PN = "2";
BODY = "Q_CAP","I19": #LOCATION = "C6" !CDS_LOCATION = "C6" #SEC = "1" !CDS_SEC = "1";
"A":   PN = "1"  !CDS_PN = "1";
"B":   PN = "2"  !CDS_PN = "2";
BODY = "Q_CAP","I21": #LOCATION = "C8" !CDS_LOCATION = "C8" #SEC = "1" !CDS_SEC = "1";
"A":   PN = "1"  !CDS_PN = "1";
"B":   PN = "2"  !CDS_PN = "2";
BODY = "Q_CAP","I23": #LOCATION = "C5" !CDS_LOCATION = "C5" #SEC = "1" !CDS_SEC = "1";
"A":   PN = "1"  !CDS_PN = "1";
"B":   PN = "2"  !CDS_PN = "2";
BODY = "Q_CAP","I24": #LOCATION = "C7" !CDS_LOCATION = "C7" #SEC = "1" !CDS_SEC = "1";
"A":   PN = "1"  !CDS_PN = "1";
"B":   PN = "2"  !CDS_PN = "2";
BODY = "Q_CAP","I25": #LOCATION = "C9" !CDS_LOCATION = "C9" #SEC = "1" !CDS_SEC = "1";
"A":   PN = "1"  !CDS_PN = "1";
"B":   PN = "2"  !CDS_PN = "2";
BODY = "Q_RES","I27": #LOCATION = "R325" !CDS_LOCATION = "R325" &SEC = "1" #&CDS_SEC = "1";
"A":   PN = "1"  !CDS_PN = "1";
"B":   PN = "2"  !CDS_PN = "2";
BODY = "Q_RES","I28": #LOCATION = "R324" !CDS_LOCATION = "R324" &SEC = "1" #&CDS_SEC = "1";
"A":   PN = "1"  !CDS_PN = "1";
"B":   PN = "2"  !CDS_PN = "2";
BODY = "Q_CAP","I32": #LOCATION = "C168" !CDS_LOCATION = "C168" &SEC = "1" #&CDS_SEC = "1";
"A":   PN = "1"  !CDS_PN = "1";
"B":   PN = "2"  !CDS_PN = "2";
BODY = "Q_CAP","I33": #LOCATION = "C170" !CDS_LOCATION = "C170" &SEC = "1" #&CDS_SEC = "1";
"A":   PN = "1"  !CDS_PN = "1";
"B":   PN = "2"  !CDS_PN = "2";
BODY = "Q_CAP","I34": #LOCATION = "C169" !CDS_LOCATION = "C169" &SEC = "1" #&CDS_SEC = "1";
"A":   PN = "1"  !CDS_PN = "1";
"B":   PN = "2"  !CDS_PN = "2";
BODY = "Q_CAP","I85": #LOCATION = "C10" !CDS_LOCATION = "C10" #SEC = "1" !CDS_SEC = "1";
"A":   PN = "1"  !CDS_PN = "1";
"B":   PN = "2"  !CDS_PN = "2";
BODY = "Q_RES","I89": #LOCATION = "R8" !CDS_LOCATION = "R8" #SEC = "1" !CDS_SEC = "1";
"A":   PN = "1"  !CDS_PN = "1";
"B":   PN = "2"  !CDS_PN = "2";
BODY = "Q_RES","I90": #LOCATION = "R7" !CDS_LOCATION = "R7" #SEC = "1" !CDS_SEC = "1";
"A":   PN = "1"  !CDS_PN = "1";
"B":   PN = "2"  !CDS_PN = "2";
BODY = "Q_CAP","I106": #LOCATION = "C12" !CDS_LOCATION = "C12" #SEC = "1" !CDS_SEC = "1";
"A":   PN = "1"  !CDS_PN = "1";
"B":   PN = "2"  !CDS_PN = "2";
BODY = "Q_CAP","I107": #LOCATION = "C229" !CDS_LOCATION = "C229" #SEC = "1" !CDS_SEC = "1";
"A":   PN = "1"  !CDS_PN = "1";
"B":   PN = "2"  !CDS_PN = "2";
BODY = "Q_RES","I111": #LOCATION = "R9" !CDS_LOCATION = "R9" #SEC = "1" !CDS_SEC = "1";
"A":   PN = "1"  !CDS_PN = "1";
"B":   PN = "2"  !CDS_PN = "2";
BODY = "Q_CAP","I113": #LOCATION = "C16" !CDS_LOCATION = "C16" #SEC = "1" !CDS_SEC = "1";
"A":   PN = "1"  !CDS_PN = "1";
"B":   PN = "2"  !CDS_PN = "2";
BODY = "Q_RES","I114": #LOCATION = "R350" !CDS_LOCATION = "R350" &SEC = "1" #&CDS_SEC = "1";
"A":   PN = "1"  !CDS_PN = "1";
"B":   PN = "2"  !CDS_PN = "2";
BODY = "Q_RES","I115": #LOCATION = "R375" !CDS_LOCATION = "R375" &SEC = "1" #&CDS_SEC = "1";
"A":   PN = "1"  !CDS_PN = "1";
"B":   PN = "2"  !CDS_PN = "2";
BODY = "Q_RES","I116": #LOCATION = "R349" !CDS_LOCATION = "R349" &SEC = "1" #&CDS_SEC = "1";
"A":   PN = "1"  !CDS_PN = "1";
"B":   PN = "2"  !CDS_PN = "2";
BODY = "Q_RES","I117": #LOCATION = "R347" !CDS_LOCATION = "R347" &SEC = "1" #&CDS_SEC = "1";
"A":   PN = "1"  !CDS_PN = "1";
"B":   PN = "2"  !CDS_PN = "2";
BODY = "Q_RES","I118": #LOCATION = "R348" !CDS_LOCATION = "R348" &SEC = "1" #&CDS_SEC = "1";
"A":   PN = "1"  !CDS_PN = "1";
"B":   PN = "2"  !CDS_PN = "2";
BODY = "Q_RES","I119": #LOCATION = "R345" !CDS_LOCATION = "R345" &SEC = "1" #&CDS_SEC = "1";
"A":   PN = "1"  !CDS_PN = "1";
"B":   PN = "2"  !CDS_PN = "2";
BODY = "Q_RES","I120": #LOCATION = "R346" !CDS_LOCATION = "R346" &SEC = "1" #&CDS_SEC = "1";
"A":   PN = "1"  !CDS_PN = "1";
"B":   PN = "2"  !CDS_PN = "2";
BODY = "Q_RES","I121": #LOCATION = "R344" !CDS_LOCATION = "R344" &SEC = "1" #&CDS_SEC = "1";
"A":   PN = "1"  !CDS_PN = "1";
"B":   PN = "2"  !CDS_PN = "2";
BODY = "Q_RES","I122": #LOCATION = "R342" !CDS_LOCATION = "R342" &SEC = "1" #&CDS_SEC = "1";
"A":   PN = "1"  !CDS_PN = "1";
"B":   PN = "2"  !CDS_PN = "2";
BODY = "Q_RES","I123": #LOCATION = "R343" !CDS_LOCATION = "R343" &SEC = "1" #&CDS_SEC = "1";
"A":   PN = "1"  !CDS_PN = "1";
"B":   PN = "2"  !CDS_PN = "2";
BODY = "Q_RES","I124": #LOCATION = "R340" !CDS_LOCATION = "R340" &SEC = "1" #&CDS_SEC = "1";
"A":   PN = "1"  !CDS_PN = "1";
"B":   PN = "2"  !CDS_PN = "2";
BODY = "Q_RES","I125": #LOCATION = "R341" !CDS_LOCATION = "R341" &SEC = "1" #&CDS_SEC = "1";
"A":   PN = "1"  !CDS_PN = "1";
"B":   PN = "2"  !CDS_PN = "2";
BODY = "Q_RES","I127": #LOCATION = "R374" !CDS_LOCATION = "R374" &SEC = "1" #&CDS_SEC = "1";
"A":   PN = "1"  !CDS_PN = "1";
"B":   PN = "2"  !CDS_PN = "2";
BODY = "Q_RES","I128": #LOCATION = "R373" !CDS_LOCATION = "R373" &SEC = "1" #&CDS_SEC = "1";
"A":   PN = "1"  !CDS_PN = "1";
"B":   PN = "2"  !CDS_PN = "2";
BODY = "Q_RES","I129": #LOCATION = "R372" !CDS_LOCATION = "R372" &SEC = "1" #&CDS_SEC = "1";
"A":   PN = "1"  !CDS_PN = "1";
"B":   PN = "2"  !CDS_PN = "2";
BODY = "Q_RES","I130": #LOCATION = "R371" !CDS_LOCATION = "R371" &SEC = "1" #&CDS_SEC = "1";
"A":   PN = "1"  !CDS_PN = "1";
"B":   PN = "2"  !CDS_PN = "2";
BODY = "Q_RES","I131": #LOCATION = "R370" !CDS_LOCATION = "R370" &SEC = "1" #&CDS_SEC = "1";
"A":   PN = "1"  !CDS_PN = "1";
"B":   PN = "2"  !CDS_PN = "2";
BODY = "Q_RES","I132": #LOCATION = "R369" !CDS_LOCATION = "R369" &SEC = "1" #&CDS_SEC = "1";
"A":   PN = "1"  !CDS_PN = "1";
"B":   PN = "2"  !CDS_PN = "2";
BODY = "Q_CAP","I134": #LOCATION = "C15" !CDS_LOCATION = "C15" #SEC = "1" !CDS_SEC = "1";
"A":   PN = "1"  !CDS_PN = "1";
"B":   PN = "2"  !CDS_PN = "2";
BODY = "Q_RES","I135": #LOCATION = "R368" !CDS_LOCATION = "R368" &SEC = "1" #&CDS_SEC = "1";
"A":   PN = "1"  !CDS_PN = "1";
"B":   PN = "2"  !CDS_PN = "2";
BODY = "Q_RES","I136": #LOCATION = "R367" !CDS_LOCATION = "R367" &SEC = "1" #&CDS_SEC = "1";
"A":   PN = "1"  !CDS_PN = "1";
"B":   PN = "2"  !CDS_PN = "2";
BODY = "Q_RES","I137": #LOCATION = "R366" !CDS_LOCATION = "R366" &SEC = "1" #&CDS_SEC = "1";
"A":   PN = "1"  !CDS_PN = "1";
"B":   PN = "2"  !CDS_PN = "2";
BODY = "Q_RES","I138": #LOCATION = "R365" !CDS_LOCATION = "R365" &SEC = "1" #&CDS_SEC = "1";
"A":   PN = "1"  !CDS_PN = "1";
"B":   PN = "2"  !CDS_PN = "2";
BODY = "Q_RES","I141": #LOCATION = "R4" !CDS_LOCATION = "R4" #SEC = "1" !CDS_SEC = "1";
"A":   PN = "1"  !CDS_PN = "1";
"B":   PN = "2"  !CDS_PN = "2";
BODY = "Q_RES","I142": #LOCATION = "R5" !CDS_LOCATION = "R5" #SEC = "1" !CDS_SEC = "1";
"A":   PN = "1"  !CDS_PN = "1";
"B":   PN = "2"  !CDS_PN = "2";
BODY = "Q_RES","I143": #LOCATION = "R6" !CDS_LOCATION = "R6" #SEC = "1" !CDS_SEC = "1";
"A":   PN = "1"  !CDS_PN = "1";
"B":   PN = "2"  !CDS_PN = "2";
BODY = "Q_RES","I159": #LOCATION = "R339" !CDS_LOCATION = "R339" &SEC = "1" #&CDS_SEC = "1";
"A":   PN = "1"  !CDS_PN = "1";
"B":   PN = "2"  !CDS_PN = "2";
BODY = "Q_RES","I160": #LOCATION = "R338" !CDS_LOCATION = "R338" &SEC = "1" #&CDS_SEC = "1";
"A":   PN = "1"  !CDS_PN = "1";
"B":   PN = "2"  !CDS_PN = "2";
BODY = "Q_RES","I161": #LOCATION = "R337" !CDS_LOCATION = "R337" &SEC = "1" #&CDS_SEC = "1";
"A":   PN = "1"  !CDS_PN = "1";
"B":   PN = "2"  !CDS_PN = "2";
BODY = "Q_RES","I162": #LOCATION = "R336" !CDS_LOCATION = "R336" &SEC = "1" #&CDS_SEC = "1";
"A":   PN = "1"  !CDS_PN = "1";
"B":   PN = "2"  !CDS_PN = "2";
BODY = "Q_RES","I163": #LOCATION = "R335" !CDS_LOCATION = "R335" &SEC = "1" #&CDS_SEC = "1";
"A":   PN = "1"  !CDS_PN = "1";
"B":   PN = "2"  !CDS_PN = "2";
BODY = "Q_RES","I164": #LOCATION = "R334" !CDS_LOCATION = "R334" &SEC = "1" #&CDS_SEC = "1";
"A":   PN = "1"  !CDS_PN = "1";
"B":   PN = "2"  !CDS_PN = "2";
BODY = "Q_RES","I165": #LOCATION = "R364" !CDS_LOCATION = "R364" &SEC = "1" #&CDS_SEC = "1";
"A":   PN = "1"  !CDS_PN = "1";
"B":   PN = "2"  !CDS_PN = "2";
BODY = "Q_RES","I166": #LOCATION = "R363" !CDS_LOCATION = "R363" &SEC = "1" #&CDS_SEC = "1";
"A":   PN = "1"  !CDS_PN = "1";
"B":   PN = "2"  !CDS_PN = "2";
BODY = "Q_RES","I167": #LOCATION = "R361" !CDS_LOCATION = "R361" &SEC = "1" #&CDS_SEC = "1";
"A":   PN = "1"  !CDS_PN = "1";
"B":   PN = "2"  !CDS_PN = "2";
BODY = "Q_RES","I168": #LOCATION = "R362" !CDS_LOCATION = "R362" &SEC = "1" #&CDS_SEC = "1";
"A":   PN = "1"  !CDS_PN = "1";
"B":   PN = "2"  !CDS_PN = "2";
BODY = "Q_RES","I169": #LOCATION = "R360" !CDS_LOCATION = "R360" &SEC = "1" #&CDS_SEC = "1";
"A":   PN = "1"  !CDS_PN = "1";
"B":   PN = "2"  !CDS_PN = "2";
BODY = "Q_RES","I170": #LOCATION = "R359" !CDS_LOCATION = "R359" &SEC = "1" #&CDS_SEC = "1";
"A":   PN = "1"  !CDS_PN = "1";
"B":   PN = "2"  !CDS_PN = "2";
BODY = "Q_RES","I171": #LOCATION = "R332" !CDS_LOCATION = "R332" &SEC = "1" #&CDS_SEC = "1";
"A":   PN = "1"  !CDS_PN = "1";
"B":   PN = "2"  !CDS_PN = "2";
BODY = "Q_RES","I172": #LOCATION = "R333" !CDS_LOCATION = "R333" &SEC = "1" #&CDS_SEC = "1";
"A":   PN = "1"  !CDS_PN = "1";
"B":   PN = "2"  !CDS_PN = "2";
BODY = "Q_RES","I173": #LOCATION = "R331" !CDS_LOCATION = "R331" &SEC = "1" #&CDS_SEC = "1";
"A":   PN = "1"  !CDS_PN = "1";
"B":   PN = "2"  !CDS_PN = "2";
BODY = "Q_RES","I174": #LOCATION = "R330" !CDS_LOCATION = "R330" &SEC = "1" #&CDS_SEC = "1";
"A":   PN = "1"  !CDS_PN = "1";
"B":   PN = "2"  !CDS_PN = "2";
BODY = "Q_RES","I175": #LOCATION = "R329" !CDS_LOCATION = "R329" &SEC = "1" #&CDS_SEC = "1";
"A":   PN = "1"  !CDS_PN = "1";
"B":   PN = "2"  !CDS_PN = "2";
BODY = "Q_RES","I176": #LOCATION = "R328" !CDS_LOCATION = "R328" &SEC = "1" #&CDS_SEC = "1";
"A":   PN = "1"  !CDS_PN = "1";
"B":   PN = "2"  !CDS_PN = "2";
BODY = "Q_RES","I177": #LOCATION = "R327" !CDS_LOCATION = "R327" &SEC = "1" #&CDS_SEC = "1";
"A":   PN = "1"  !CDS_PN = "1";
"B":   PN = "2"  !CDS_PN = "2";
BODY = "Q_RES","I178": #LOCATION = "R358" !CDS_LOCATION = "R358" &SEC = "1" #&CDS_SEC = "1";
"A":   PN = "1"  !CDS_PN = "1";
"B":   PN = "2"  !CDS_PN = "2";
BODY = "Q_RES","I179": #LOCATION = "R357" !CDS_LOCATION = "R357" &SEC = "1" #&CDS_SEC = "1";
"A":   PN = "1"  !CDS_PN = "1";
"B":   PN = "2"  !CDS_PN = "2";
BODY = "Q_RES","I180": #LOCATION = "R356" !CDS_LOCATION = "R356" &SEC = "1" #&CDS_SEC = "1";
"A":   PN = "1"  !CDS_PN = "1";
"B":   PN = "2"  !CDS_PN = "2";
BODY = "Q_RES","I181": #LOCATION = "R354" !CDS_LOCATION = "R354" &SEC = "1" #&CDS_SEC = "1";
"A":   PN = "1"  !CDS_PN = "1";
"B":   PN = "2"  !CDS_PN = "2";
BODY = "Q_RES","I182": #LOCATION = "R355" !CDS_LOCATION = "R355" &SEC = "1" #&CDS_SEC = "1";
"A":   PN = "1"  !CDS_PN = "1";
"B":   PN = "2"  !CDS_PN = "2";
BODY = "Q_RES","I183": #LOCATION = "R353" !CDS_LOCATION = "R353" &SEC = "1" #&CDS_SEC = "1";
"A":   PN = "1"  !CDS_PN = "1";
"B":   PN = "2"  !CDS_PN = "2";
BODY = "Q_RES","I184": #LOCATION = "R352" !CDS_LOCATION = "R352" &SEC = "1" #&CDS_SEC = "1";
"A":   PN = "1"  !CDS_PN = "1";
"B":   PN = "2"  !CDS_PN = "2";
BODY = "Q_CAP","I186": #LOCATION = "C13" !CDS_LOCATION = "C13" #SEC = "1" !CDS_SEC = "1";
"A":   PN = "1"  !CDS_PN = "1";
"B":   PN = "2"  !CDS_PN = "2";
BODY = "Q_CAP","I187": #LOCATION = "C14" !CDS_LOCATION = "C14" #SEC = "1" !CDS_SEC = "1";
"A":   PN = "1"  !CDS_PN = "1";
"B":   PN = "2"  !CDS_PN = "2";
BODY = "Q_CAP","I190": #LOCATION = "C17" !CDS_LOCATION = "C17" #SEC = "1" !CDS_SEC = "1";
"A":   PN = "1"  !CDS_PN = "1";
"B":   PN = "2"  !CDS_PN = "2";
BODY = "Q_CAP","I192": #LOCATION = "C18" !CDS_LOCATION = "C18" #SEC = "1" !CDS_SEC = "1";
"A":   PN = "1"  !CDS_PN = "1";
"B":   PN = "2"  !CDS_PN = "2";
BODY = "Q_RES","I193": #LOCATION = "R326" !CDS_LOCATION = "R326" &SEC = "1" #&CDS_SEC = "1";
"A":   PN = "1"  !CDS_PN = "1";
"B":   PN = "2"  !CDS_PN = "2";
BODY = "Q_RES","I194": #LOCATION = "R351" !CDS_LOCATION = "R351" &SEC = "1" #&CDS_SEC = "1";
"A":   PN = "1"  !CDS_PN = "1";
"B":   PN = "2"  !CDS_PN = "2";
BODY = "K4A8G165WCBCTD","I196": #LOCATION = "U1" !CDS_LOCATION = "U1" &SEC = "1" #&CDS_SEC = "1";
"A0":   PN = "P3"  !CDS_PN = "P3";
"A1":   PN = "P7"  !CDS_PN = "P7";
"A2":   PN = "R3"  !CDS_PN = "R3";
"A3":   PN = "N7"  !CDS_PN = "N7";
"A4":   PN = "N3"  !CDS_PN = "N3";
"A5":   PN = "P8"  !CDS_PN = "P8";
"A6":   PN = "P2"  !CDS_PN = "P2";
"A7":   PN = "R8"  !CDS_PN = "R8";
"A8":   PN = "R2"  !CDS_PN = "R2";
"A9":   PN = "R7"  !CDS_PN = "R7";
"A10||AP":   PN = "M3"  !CDS_PN = "M3";
"A11":   PN = "T2"  !CDS_PN = "T2";
"A12||BC_N":   PN = "M7"  !CDS_PN = "M7";
"A13":   PN = "T8"  !CDS_PN = "T8";
"ACT_N":   PN = "L3"  !CDS_PN = "L3";
"ALERT_N":   PN = "P9"  !CDS_PN = "P9";
"BA0":   PN = "N2"  !CDS_PN = "N2";
"BA1":   PN = "N8"  !CDS_PN = "N8";
"BG0":   PN = "M2"  !CDS_PN = "M2";
"CAS_N||A15":   PN = "M8"  !CDS_PN = "M8";
"CK_C":   PN = "K8"  !CDS_PN = "K8";
"CK_T":   PN = "K7"  !CDS_PN = "K7";
"CKE":   PN = "K2"  !CDS_PN = "K2";
"CS_N":   PN = "L7"  !CDS_PN = "L7";
"DML_N||DBIL_N":   PN = "E7"  !CDS_PN = "E7";
"DMU_N||DBIU_N":   PN = "E2"  !CDS_PN = "E2";
"DQL0":   PN = "G2"  !CDS_PN = "G2";
"DQL1":   PN = "F7"  !CDS_PN = "F7";
"DQL2":   PN = "H3"  !CDS_PN = "H3";
"DQL3":   PN = "H7"  !CDS_PN = "H7";
"DQL4":   PN = "H2"  !CDS_PN = "H2";
"DQL5":   PN = "H8"  !CDS_PN = "H8";
"DQL6":   PN = "J3"  !CDS_PN = "J3";
"DQL7":   PN = "J7"  !CDS_PN = "J7";
"DQSL_C":   PN = "F3"  !CDS_PN = "F3";
"DQSL_T":   PN = "G3"  !CDS_PN = "G3";
"DQSU_C":   PN = "A7"  !CDS_PN = "A7";
"DQSU_T":   PN = "B7"  !CDS_PN = "B7";
"DQU0":   PN = "A3"  !CDS_PN = "A3";
"DQU1":   PN = "B8"  !CDS_PN = "B8";
"DQU2":   PN = "C3"  !CDS_PN = "C3";
"DQU3":   PN = "C7"  !CDS_PN = "C7";
"DQU4":   PN = "C2"  !CDS_PN = "C2";
"DQU5":   PN = "C8"  !CDS_PN = "C8";
"DQU6":   PN = "D3"  !CDS_PN = "D3";
"DQU7":   PN = "D7"  !CDS_PN = "D7";
"NC1":   PN = "T7"  !CDS_PN = "T7";
"ODT":   PN = "K3"  !CDS_PN = "K3";
"PAR":   PN = "T3"  !CDS_PN = "T3";
"RAS_N":   PN = "L8"  !CDS_PN = "L8";
"RESET_N":   PN = "P1"  !CDS_PN = "P1";
"TEN":   PN = "N9"  !CDS_PN = "N9";
"VDD0":   PN = "B3"  !CDS_PN = "B3";
"VDD1":   PN = "B9"  !CDS_PN = "B9";
"VDD2":   PN = "D1"  !CDS_PN = "D1";
"VDD3":   PN = "G7"  !CDS_PN = "G7";
"VDD4":   PN = "J1"  !CDS_PN = "J1";
"VDD5":   PN = "J9"  !CDS_PN = "J9";
"VDD6":   PN = "L1"  !CDS_PN = "L1";
"VDD7":   PN = "L9"  !CDS_PN = "L9";
"VDD8":   PN = "R1"  !CDS_PN = "R1";
"VDD9":   PN = "T9"  !CDS_PN = "T9";
"VDDQ0":   PN = "A1"  !CDS_PN = "A1";
"VDDQ1":   PN = "A9"  !CDS_PN = "A9";
"VDDQ2":   PN = "C1"  !CDS_PN = "C1";
"VDDQ3":   PN = "D9"  !CDS_PN = "D9";
"VDDQ4":   PN = "F2"  !CDS_PN = "F2";
"VDDQ5":   PN = "F8"  !CDS_PN = "F8";
"VDDQ6":   PN = "G1"  !CDS_PN = "G1";
"VDDQ7":   PN = "G9"  !CDS_PN = "G9";
"VDDQ8":   PN = "J2"  !CDS_PN = "J2";
"VDDQ9":   PN = "J8"  !CDS_PN = "J8";
"VPP0":   PN = "B1"  !CDS_PN = "B1";
"VPP1":   PN = "R9"  !CDS_PN = "R9";
"VREFCA":   PN = "M1"  !CDS_PN = "M1";
"VSS0":   PN = "B2"  !CDS_PN = "B2";
"VSS1":   PN = "E1"  !CDS_PN = "E1";
"VSS2":   PN = "E9"  !CDS_PN = "E9";
"VSS3":   PN = "G8"  !CDS_PN = "G8";
"VSS4":   PN = "K1"  !CDS_PN = "K1";
"VSS5":   PN = "K9"  !CDS_PN = "K9";
"VSS6":   PN = "M9"  !CDS_PN = "M9";
"VSS7":   PN = "N1"  !CDS_PN = "N1";
"VSS8":   PN = "T1"  !CDS_PN = "T1";
"VSSQ0":   PN = "A2"  !CDS_PN = "A2";
"VSSQ1":   PN = "A8"  !CDS_PN = "A8";
"VSSQ2":   PN = "C9"  !CDS_PN = "C9";
"VSSQ3":   PN = "D2"  !CDS_PN = "D2";
"VSSQ4":   PN = "D8"  !CDS_PN = "D8";
"VSSQ5":   PN = "E3"  !CDS_PN = "E3";
"VSSQ6":   PN = "E8"  !CDS_PN = "E8";
"VSSQ7":   PN = "F1"  !CDS_PN = "F1";
"VSSQ8":   PN = "H1"  !CDS_PN = "H1";
"VSSQ9":   PN = "H9"  !CDS_PN = "H9";
"WE_N||A14":   PN = "L2"  !CDS_PN = "L2";
"ZQ":   PN = "F9"  !CDS_PN = "F9";
BODY = "Q_CAP","I197": #LOCATION = "C225" !CDS_LOCATION = "C225" #SEC = "1" !CDS_SEC = "1";
"A":   PN = "1"  !CDS_PN = "1";
"B":   PN = "2"  !CDS_PN = "2";
BODY = "Q_CAP","I198": #LOCATION = "C222" !CDS_LOCATION = "C222" #SEC = "1" !CDS_SEC = "1";
"A":   PN = "1"  !CDS_PN = "1";
"B":   PN = "2"  !CDS_PN = "2";
BODY = "Q_CAP","I199": #LOCATION = "C221" !CDS_LOCATION = "C221" #SEC = "1" !CDS_SEC = "1";
"A":   PN = "1"  !CDS_PN = "1";
"B":   PN = "2"  !CDS_PN = "2";
DRAWING = "@scm_lib.scm(sch_1):page21";
BODY = "Q_CAP","I21": #LOCATION = "C228" !CDS_LOCATION = "C228" &SEC = "1" #&CDS_SEC = "1";
"A":   PN = "1"  !CDS_PN = "1";
"B":   PN = "2"  !CDS_PN = "2";
BODY = "Q_RES","I33": #LOCATION = "R654" !CDS_LOCATION = "R654" &SEC = "1" #&CDS_SEC = "1";
"A":   PN = "1"  !CDS_PN = "1";
"B":   PN = "2"  !CDS_PN = "2";
BODY = "Q_RES","I35": #LOCATION = "R48" !CDS_LOCATION = "R48" &SEC = "1" #&CDS_SEC = "1";
"A":   PN = "1"  !CDS_PN = "1";
"B":   PN = "2"  !CDS_PN = "2";
BODY = "Q_RES","I42": #LOCATION = "R649" !CDS_LOCATION = "R649" &SEC = "1" #&CDS_SEC = "1";
"A":   PN = "1"  !CDS_PN = "1";
"B":   PN = "2"  !CDS_PN = "2";
BODY = "Q_RES","I43": #LOCATION = "R648" !CDS_LOCATION = "R648" &SEC = "1" #&CDS_SEC = "1";
"A":   PN = "1"  !CDS_PN = "1";
"B":   PN = "2"  !CDS_PN = "2";
BODY = "Q_RES","I45": #LOCATION = "R647" !CDS_LOCATION = "R647" &SEC = "1" #&CDS_SEC = "1";
"A":   PN = "1"  !CDS_PN = "1";
"B":   PN = "2"  !CDS_PN = "2";
BODY = "Q_RES","I46": #LOCATION = "R532" !CDS_LOCATION = "R532" &SEC = "1" #&CDS_SEC = "1";
"A":   PN = "1"  !CDS_PN = "1";
"B":   PN = "2"  !CDS_PN = "2";
BODY = "Q_RES","I58": #LOCATION = "R662" !CDS_LOCATION = "R662" &SEC = "1" #&CDS_SEC = "1";
"A":   PN = "1"  !CDS_PN = "1";
"B":   PN = "2"  !CDS_PN = "2";
BODY = "Q_RES","I59": #LOCATION = "R663" !CDS_LOCATION = "R663" &SEC = "1" #&CDS_SEC = "1";
"A":   PN = "1"  !CDS_PN = "1";
"B":   PN = "2"  !CDS_PN = "2";
BODY = "Q_RES","I60": #LOCATION = "R661" !CDS_LOCATION = "R661" &SEC = "1" #&CDS_SEC = "1";
"A":   PN = "1"  !CDS_PN = "1";
"B":   PN = "2"  !CDS_PN = "2";
BODY = "Q_RES","I61": #LOCATION = "R660" !CDS_LOCATION = "R660" &SEC = "1" #&CDS_SEC = "1";
"A":   PN = "1"  !CDS_PN = "1";
"B":   PN = "2"  !CDS_PN = "2";
BODY = "Q_RES","I62": #LOCATION = "R658" !CDS_LOCATION = "R658" &SEC = "1" #&CDS_SEC = "1";
"A":   PN = "1"  !CDS_PN = "1";
"B":   PN = "2"  !CDS_PN = "2";
BODY = "Q_RES","I63": #LOCATION = "R657" !CDS_LOCATION = "R657" &SEC = "1" #&CDS_SEC = "1";
"A":   PN = "1"  !CDS_PN = "1";
"B":   PN = "2"  !CDS_PN = "2";
BODY = "Q_RES","I64": #LOCATION = "R659" !CDS_LOCATION = "R659" &SEC = "1" #&CDS_SEC = "1";
"A":   PN = "1"  !CDS_PN = "1";
"B":   PN = "2"  !CDS_PN = "2";
BODY = "Q_RES","I66": #LOCATION = "R656" !CDS_LOCATION = "R656" &SEC = "1" #&CDS_SEC = "1";
"A":   PN = "1"  !CDS_PN = "1";
"B":   PN = "2"  !CDS_PN = "2";
BODY = "Q_RES","I67": #LOCATION = "R655" !CDS_LOCATION = "R655" &SEC = "1" #&CDS_SEC = "1";
"A":   PN = "1"  !CDS_PN = "1";
"B":   PN = "2"  !CDS_PN = "2";
BODY = "Q_CAP","I80": #LOCATION = "C235" !CDS_LOCATION = "C235" &SEC = "1" #&CDS_SEC = "1";
"A":   PN = "1"  !CDS_PN = "1";
"B":   PN = "2"  !CDS_PN = "2";
BODY = "Q_CAP","I81": #LOCATION = "C234" !CDS_LOCATION = "C234" &SEC = "1" #&CDS_SEC = "1";
"A":   PN = "1"  !CDS_PN = "1";
"B":   PN = "2"  !CDS_PN = "2";
BODY = "SCONN67_NASA0S6730TS67","I84": LOCATION = "J4" #&CDS_LOCATION = "J4" &SEC = "1" #&CDS_SEC = "1";
"1":   PN = "1"  !CDS_PN = "1";
"2":   PN = "2"  !CDS_PN = "2";
"3":   PN = "3"  !CDS_PN = "3";
"4":   PN = "4"  !CDS_PN = "4";
"5":   PN = "5"  !CDS_PN = "5";
"6":   PN = "6"  !CDS_PN = "6";
"7":   PN = "7"  !CDS_PN = "7";
"16":   PN = "16"  !CDS_PN = "16";
"17":   PN = "17"  !CDS_PN = "17";
"18":   PN = "18"  !CDS_PN = "18";
"19":   PN = "19"  !CDS_PN = "19";
"20":   PN = "20"  !CDS_PN = "20";
"21":   PN = "21"  !CDS_PN = "21";
"22":   PN = "22"  !CDS_PN = "22";
"23":   PN = "23"  !CDS_PN = "23";
"24":   PN = "24"  !CDS_PN = "24";
"25":   PN = "25"  !CDS_PN = "25";
"26":   PN = "26"  !CDS_PN = "26";
"27":   PN = "27"  !CDS_PN = "27";
"28":   PN = "28"  !CDS_PN = "28";
"29":   PN = "29"  !CDS_PN = "29";
"30":   PN = "30"  !CDS_PN = "30";
"31":   PN = "31"  !CDS_PN = "31";
"32":   PN = "32"  !CDS_PN = "32";
"33":   PN = "33"  !CDS_PN = "33";
"34":   PN = "34"  !CDS_PN = "34";
"35":   PN = "35"  !CDS_PN = "35";
"36":   PN = "36"  !CDS_PN = "36";
"37":   PN = "37"  !CDS_PN = "37";
"38":   PN = "38"  !CDS_PN = "38";
"39":   PN = "39"  !CDS_PN = "39";
"40":   PN = "40"  !CDS_PN = "40";
"41":   PN = "41"  !CDS_PN = "41";
"42":   PN = "42"  !CDS_PN = "42";
"43":   PN = "43"  !CDS_PN = "43";
"44":   PN = "44"  !CDS_PN = "44";
"45":   PN = "45"  !CDS_PN = "45";
"46":   PN = "46"  !CDS_PN = "46";
"47":   PN = "47"  !CDS_PN = "47";
"48":   PN = "48"  !CDS_PN = "48";
"49":   PN = "49"  !CDS_PN = "49";
"50":   PN = "50"  !CDS_PN = "50";
"51":   PN = "51"  !CDS_PN = "51";
"52":   PN = "52"  !CDS_PN = "52";
"53":   PN = "53"  !CDS_PN = "53";
"54":   PN = "54"  !CDS_PN = "54";
"55":   PN = "55"  !CDS_PN = "55";
"56":   PN = "56"  !CDS_PN = "56";
"57":   PN = "57"  !CDS_PN = "57";
"58":   PN = "58"  !CDS_PN = "58";
"59":   PN = "59"  !CDS_PN = "59";
"60":   PN = "60"  !CDS_PN = "60";
"61":   PN = "61"  !CDS_PN = "61";
"62":   PN = "62"  !CDS_PN = "62";
"63":   PN = "63"  !CDS_PN = "63";
"64":   PN = "64"  !CDS_PN = "64";
"65":   PN = "65"  !CDS_PN = "65";
"66":   PN = "66"  !CDS_PN = "66";
"67":   PN = "67"  !CDS_PN = "67";
"68":   PN = "68"  !CDS_PN = "68";
"69":   PN = "69"  !CDS_PN = "69";
"70":   PN = "70"  !CDS_PN = "70";
"71":   PN = "71"  !CDS_PN = "71";
"72":   PN = "72"  !CDS_PN = "72";
"73":   PN = "73"  !CDS_PN = "73";
"74":   PN = "74"  !CDS_PN = "74";
"75":   PN = "75"  !CDS_PN = "75";
"G1":   PN = "G1"  !CDS_PN = "G1";
"G2":   PN = "G2"  !CDS_PN = "G2";
BODY = "Q_RES","I98": #LOCATION = "R651" !CDS_LOCATION = "R651" &SEC = "1" #&CDS_SEC = "1";
"A":   PN = "1"  !CDS_PN = "1";
"B":   PN = "2"  !CDS_PN = "2";
BODY = "Q_RES","I99": #LOCATION = "R650" !CDS_LOCATION = "R650" &SEC = "1" #&CDS_SEC = "1";
"A":   PN = "1"  !CDS_PN = "1";
"B":   PN = "2"  !CDS_PN = "2";
BODY = "Q_RES","I100": #LOCATION = "R653" !CDS_LOCATION = "R653" &SEC = "1" #&CDS_SEC = "1";
"A":   PN = "1"  !CDS_PN = "1";
"B":   PN = "2"  !CDS_PN = "2";
BODY = "Q_RES","I101": #LOCATION = "R652" !CDS_LOCATION = "R652" &SEC = "1" #&CDS_SEC = "1";
"A":   PN = "1"  !CDS_PN = "1";
"B":   PN = "2"  !CDS_PN = "2";
BODY = "Q_RES","I125": #LOCATION = "R665" !CDS_LOCATION = "R665" #SEC = "1" !CDS_SEC = "1";
"A":   PN = "1"  !CDS_PN = "1";
"B":   PN = "2"  !CDS_PN = "2";
BODY = "Q_RES","I128": #LOCATION = "R664" !CDS_LOCATION = "R664" #SEC = "1" !CDS_SEC = "1";
"A":   PN = "1"  !CDS_PN = "1";
"B":   PN = "2"  !CDS_PN = "2";
BODY = "Q_RES","I147": LOCATION = "R543" #&CDS_LOCATION = "R543" &SEC = "1" #&CDS_SEC = "1";
"A":   PN = "1"  !CDS_PN = "1";
"B":   PN = "2"  !CDS_PN = "2";
BODY = "Q_RES","I156": LOCATION = "R850" #&CDS_LOCATION = "R850" #SEC = "1" !CDS_SEC = "1";
"A":   PN = "1"  !CDS_PN = "1";
"B":   PN = "2"  !CDS_PN = "2";
BODY = "Q_RES","I157": LOCATION = "R849" #&CDS_LOCATION = "R849" #SEC = "1" !CDS_SEC = "1";
"A":   PN = "1"  !CDS_PN = "1";
"B":   PN = "2"  !CDS_PN = "2";
BODY = "Q_RES","I161": LOCATION = "R867" #&CDS_LOCATION = "R867" &SEC = "1" #&CDS_SEC = "1";
"A":   PN = "1"  !CDS_PN = "1";
"B":   PN = "2"  !CDS_PN = "2";
BODY = "Q_RES","I166": LOCATION = "R404" #&CDS_LOCATION = "R404" &SEC = "1" #&CDS_SEC = "1";
"A":   PN = "1"  !CDS_PN = "1";
"B":   PN = "2"  !CDS_PN = "2";
BODY = "Q_RES","I167": LOCATION = "R57" #&CDS_LOCATION = "R57" &SEC = "1" #&CDS_SEC = "1";
"A":   PN = "1"  !CDS_PN = "1";
"B":   PN = "2"  !CDS_PN = "2";
BODY = "Q_RES","I168": LOCATION = "R58" #&CDS_LOCATION = "R58" &SEC = "1" #&CDS_SEC = "1";
"A":   PN = "1"  !CDS_PN = "1";
"B":   PN = "2"  !CDS_PN = "2";
BODY = "Q_RES","I172": #LOCATION = "R11" !CDS_LOCATION = "R11" &SEC = "1" #&CDS_SEC = "1";
"A":   PN = "1"  !CDS_PN = "1";
"B":   PN = "2"  !CDS_PN = "2";
BODY = "Q_RES","I173": #LOCATION = "R557" !CDS_LOCATION = "R557" &SEC = "1" #&CDS_SEC = "1";
"A":   PN = "1"  !CDS_PN = "1";
"B":   PN = "2"  !CDS_PN = "2";
BODY = "Q_RES","I174": #LOCATION = "R558" !CDS_LOCATION = "R558" &SEC = "1" #&CDS_SEC = "1";
"A":   PN = "1"  !CDS_PN = "1";
"B":   PN = "2"  !CDS_PN = "2";
BODY = "Q_RES","I175": #LOCATION = "R553" !CDS_LOCATION = "R553" &SEC = "1" #&CDS_SEC = "1";
"A":   PN = "1"  !CDS_PN = "1";
"B":   PN = "2"  !CDS_PN = "2";
BODY = "Q_RES","I176": #LOCATION = "R547" !CDS_LOCATION = "R547" &SEC = "1" #&CDS_SEC = "1";
"A":   PN = "1"  !CDS_PN = "1";
"B":   PN = "2"  !CDS_PN = "2";
BODY = "Q_RES","I177": #LOCATION = "R549" !CDS_LOCATION = "R549" &SEC = "1" #&CDS_SEC = "1";
"A":   PN = "1"  !CDS_PN = "1";
"B":   PN = "2"  !CDS_PN = "2";
BODY = "Q_RES","I178": #LOCATION = "R550" !CDS_LOCATION = "R550" &SEC = "1" #&CDS_SEC = "1";
"A":   PN = "1"  !CDS_PN = "1";
"B":   PN = "2"  !CDS_PN = "2";
BODY = "Q_RES","I179": #LOCATION = "R552" !CDS_LOCATION = "R552" &SEC = "1" #&CDS_SEC = "1";
"A":   PN = "1"  !CDS_PN = "1";
"B":   PN = "2"  !CDS_PN = "2";
BODY = "Q_RES","I180": #LOCATION = "R562" !CDS_LOCATION = "R562" &SEC = "1" #&CDS_SEC = "1";
"A":   PN = "1"  !CDS_PN = "1";
"B":   PN = "2"  !CDS_PN = "2";
BODY = "Q_RES","I181": #LOCATION = "R561" !CDS_LOCATION = "R561" &SEC = "1" #&CDS_SEC = "1";
"A":   PN = "1"  !CDS_PN = "1";
"B":   PN = "2"  !CDS_PN = "2";
BODY = "Q_RES","I182": #LOCATION = "R90" !CDS_LOCATION = "R90" &SEC = "1" #&CDS_SEC = "1";
"A":   PN = "1"  !CDS_PN = "1";
"B":   PN = "2"  !CDS_PN = "2";
DRAWING = "@scm_lib.scm(sch_1):page22";
BODY = "MMBT39047F","I2": #LOCATION = "Q1" !CDS_LOCATION = "Q1" #SEC = "1" !CDS_SEC = "1";
"1":   PN = "B"  !CDS_PN = "B";
"2":   PN = "E"  !CDS_PN = "E";
"3":   PN = "C"  !CDS_PN = "C";
BODY = "MMBT39047F","I4": #LOCATION = "Q3" !CDS_LOCATION = "Q3" #SEC = "1" !CDS_SEC = "1";
"1":   PN = "B"  !CDS_PN = "B";
"2":   PN = "E"  !CDS_PN = "E";
"3":   PN = "C"  !CDS_PN = "C";
BODY = "Q_RES","I5": #LOCATION = "R287" !CDS_LOCATION = "R287" &SEC = "1" #&CDS_SEC = "1";
"A":   PN = "1"  !CDS_PN = "1";
"B":   PN = "2"  !CDS_PN = "2";
BODY = "Q_RES","I7": #LOCATION = "R289" !CDS_LOCATION = "R289" &SEC = "1" #&CDS_SEC = "1";
"A":   PN = "1"  !CDS_PN = "1";
"B":   PN = "2"  !CDS_PN = "2";
BODY = "Q_RES","I8": #LOCATION = "R290" !CDS_LOCATION = "R290" &SEC = "1" #&CDS_SEC = "1";
"A":   PN = "1"  !CDS_PN = "1";
"B":   PN = "2"  !CDS_PN = "2";
BODY = "Q_RES","I9": #LOCATION = "R291" !CDS_LOCATION = "R291" &SEC = "1" #&CDS_SEC = "1";
"A":   PN = "1"  !CDS_PN = "1";
"B":   PN = "2"  !CDS_PN = "2";
BODY = "Q_RES","I10": #LOCATION = "R636" !CDS_LOCATION = "R636" &SEC = "1" #&CDS_SEC = "1";
"A":   PN = "1"  !CDS_PN = "1";
"B":   PN = "2"  !CDS_PN = "2";
BODY = "Q_RES","I12": #LOCATION = "R106" !CDS_LOCATION = "R106" &SEC = "1" #&CDS_SEC = "1";
"A":   PN = "1"  !CDS_PN = "1";
"B":   PN = "2"  !CDS_PN = "2";
BODY = "MOSFET_N","I14": #LOCATION = "U12" !CDS_LOCATION = "U12" &SEC = "1" #&CDS_SEC = "1";
"DRAIN":   PN = "D"  !CDS_PN = "D";
"GATE":   PN = "G"  !CDS_PN = "G";
"SOURCE":   PN = "S"  !CDS_PN = "S";
BODY = "Q_CAP","I17": #LOCATION = "C147" !CDS_LOCATION = "C147" #SEC = "1" !CDS_SEC = "1";
"A":   PN = "1"  !CDS_PN = "1";
"B":   PN = "2"  !CDS_PN = "2";
BODY = "Q_CAP","I23": #LOCATION = "C161" !CDS_LOCATION = "C161" &SEC = "1" #&CDS_SEC = "1";
"A":   PN = "1"  !CDS_PN = "1";
"B":   PN = "2"  !CDS_PN = "2";
BODY = "Q_RES","I26": #LOCATION = "R314" !CDS_LOCATION = "R314" &SEC = "1" #&CDS_SEC = "1";
"A":   PN = "1"  !CDS_PN = "1";
"B":   PN = "2"  !CDS_PN = "2";
BODY = "Q_DIODE","I28": #LOCATION = "D17" !CDS_LOCATION = "D17" &SEC = "1" #&CDS_SEC = "1";
"1":   PN = "1"  !CDS_PN = "1";
"2":   PN = "2"  !CDS_PN = "2";
BODY = "Q_RES","I30": #LOCATION = "R313" !CDS_LOCATION = "R313" &SEC = "1" #&CDS_SEC = "1";
"A":   PN = "1"  !CDS_PN = "1";
"B":   PN = "2"  !CDS_PN = "2";
BODY = "Q_RES","I35": #LOCATION = "R614" !CDS_LOCATION = "R614" &SEC = "1" #&CDS_SEC = "1";
"A":   PN = "1"  !CDS_PN = "1";
"B":   PN = "2"  !CDS_PN = "2";
BODY = "Q_RES","I41": #LOCATION = "R192" !CDS_LOCATION = "R192" &SEC = "1" #&CDS_SEC = "1";
"A":   PN = "1"  !CDS_PN = "1";
"B":   PN = "2"  !CDS_PN = "2";
BODY = "Q_CAP","I42": #LOCATION = "C34" !CDS_LOCATION = "C34" &SEC = "1" #&CDS_SEC = "1";
"A":   PN = "1"  !CDS_PN = "1";
"B":   PN = "2"  !CDS_PN = "2";
BODY = "Q_CAP","I46": #LOCATION = "C223" !CDS_LOCATION = "C223" &SEC = "1" #&CDS_SEC = "1";
"A":   PN = "1"  !CDS_PN = "1";
"B":   PN = "2"  !CDS_PN = "2";
BODY = "Q_RES","I49": #LOCATION = "R711" !CDS_LOCATION = "R711" &SEC = "1" #&CDS_SEC = "1";
"A":   PN = "1"  !CDS_PN = "1";
"B":   PN = "2"  !CDS_PN = "2";
BODY = "Q_RES","I55": #LOCATION = "R710" !CDS_LOCATION = "R710" &SEC = "1" #&CDS_SEC = "1";
"A":   PN = "1"  !CDS_PN = "1";
"B":   PN = "2"  !CDS_PN = "2";
BODY = "Q_CAP","I57": #LOCATION = "C253" !CDS_LOCATION = "C253" &SEC = "1" #&CDS_SEC = "1";
"A":   PN = "1"  !CDS_PN = "1";
"B":   PN = "2"  !CDS_PN = "2";
BODY = "Q_CAP","I59": #LOCATION = "C264" !CDS_LOCATION = "C264" &SEC = "1" #&CDS_SEC = "1";
"A":   PN = "1"  !CDS_PN = "1";
"B":   PN = "2"  !CDS_PN = "2";
BODY = "Q_RES","I65": #LOCATION = "R108" !CDS_LOCATION = "R108" &SEC = "1" #&CDS_SEC = "1";
"A":   PN = "1"  !CDS_PN = "1";
"B":   PN = "2"  !CDS_PN = "2";
BODY = "Q_RES","I67": #LOCATION = "R124" !CDS_LOCATION = "R124" &SEC = "1" #&CDS_SEC = "1";
"A":   PN = "1"  !CDS_PN = "1";
"B":   PN = "2"  !CDS_PN = "2";
BODY = "Q_RES","I69": #LOCATION = "R125" !CDS_LOCATION = "R125" &SEC = "1" #&CDS_SEC = "1";
"A":   PN = "1"  !CDS_PN = "1";
"B":   PN = "2"  !CDS_PN = "2";
BODY = "Q_RES","I71": #LOCATION = "R315" !CDS_LOCATION = "R315" &SEC = "1" #&CDS_SEC = "1";
"A":   PN = "1"  !CDS_PN = "1";
"B":   PN = "2"  !CDS_PN = "2";
BODY = "Q_RES","I72": #LOCATION = "R49" !CDS_LOCATION = "R49" &SEC = "1" #&CDS_SEC = "1";
"A":   PN = "1"  !CDS_PN = "1";
"B":   PN = "2"  !CDS_PN = "2";
BODY = "Q_RES","I74": #LOCATION = "R451" !CDS_LOCATION = "R451" &SEC = "1" #&CDS_SEC = "1";
"A":   PN = "1"  !CDS_PN = "1";
"B":   PN = "2"  !CDS_PN = "2";
BODY = "Q_RES","I81": #LOCATION = "R633" !CDS_LOCATION = "R633" #SEC = "1" !CDS_SEC = "1";
"A":   PN = "1"  !CDS_PN = "1";
"B":   PN = "2"  !CDS_PN = "2";
BODY = "Q_RES","I83": #LOCATION = "R751" !CDS_LOCATION = "R751" &SEC = "1" #&CDS_SEC = "1";
"A":   PN = "1"  !CDS_PN = "1";
"B":   PN = "2"  !CDS_PN = "2";
BODY = "74LVC2G07DW7","I87": #LOCATION = "U6" !CDS_LOCATION = "U6" &SEC = "1" #&CDS_SEC = "1";
"1A":   PN = "1"  !CDS_PN = "1";
"1Y":   PN = "6"  !CDS_PN = "6";
"2A":   PN = "3"  !CDS_PN = "3";
"2Y":   PN = "4"  !CDS_PN = "4";
"GND":   PN = "2"  !CDS_PN = "2";
"VCC":   PN = "5"  !CDS_PN = "5";
BODY = "MC74VHC1G07DFT2G","I89": #LOCATION = "U13" !CDS_LOCATION = "U13" &SEC = "1" #&CDS_SEC = "1";
"GND":   PN = "3"  !CDS_PN = "3";
"IN_A":   PN = "2"  !CDS_PN = "2";
"NC1":   PN = "1"  !CDS_PN = "1";
"OUT_Y":   PN = "4"  !CDS_PN = "4";
"VCC":   PN = "5"  !CDS_PN = "5";
BODY = "TPS3808G18DBVR","I90": #LOCATION = "U43" !CDS_LOCATION = "U43" &SEC = "1" #&CDS_SEC = "1";
"#MR":   PN = "3"  !CDS_PN = "3";
"#RESET":   PN = "1"  !CDS_PN = "1";
"CT":   PN = "4"  !CDS_PN = "4";
"GND":   PN = "2"  !CDS_PN = "2";
"SENSE":   PN = "5"  !CDS_PN = "5";
"VDD":   PN = "6"  !CDS_PN = "6";
BODY = "Q_RES","I92": LOCATION = "R388" #&CDS_LOCATION = "R388" &SEC = "1" #&CDS_SEC = "1";
"A":   PN = "1"  !CDS_PN = "1";
"B":   PN = "2"  !CDS_PN = "2";
BODY = "MC74VHC1G32DTT1G","I94": LOCATION = "U58" #&CDS_LOCATION = "U58" &SEC = "1" #&CDS_SEC = "1";
"GND":   PN = "3"  !CDS_PN = "3";
"IN_A":   PN = "2"  !CDS_PN = "2";
"IN_B":   PN = "1"  !CDS_PN = "1";
"OUT_Y":   PN = "4"  !CDS_PN = "4";
"VCC":   PN = "5"  !CDS_PN = "5";
BODY = "Q_CAP","I97": LOCATION = "C337" #&CDS_LOCATION = "C337" &SEC = "1" #&CDS_SEC = "1";
"A":   PN = "1"  !CDS_PN = "1";
"B":   PN = "2"  !CDS_PN = "2";
BODY = "Q_RES","I100": #LOCATION = "R282" !CDS_LOCATION = "R282" &SEC = "1" #&CDS_SEC = "1";
"A":   PN = "1"  !CDS_PN = "1";
"B":   PN = "2"  !CDS_PN = "2";
BODY = "Q_RES","I101": #LOCATION = "R450" !CDS_LOCATION = "R450" &SEC = "1" #&CDS_SEC = "1";
"A":   PN = "1"  !CDS_PN = "1";
"B":   PN = "2"  !CDS_PN = "2";
BODY = "Q_RES","I102": LOCATION = "R888" #&CDS_LOCATION = "R888" &SEC = "1" #&CDS_SEC = "1";
"A":   PN = "1"  !CDS_PN = "1";
"B":   PN = "2"  !CDS_PN = "2";
BODY = "Q_RES","I106": LOCATION = "R887" #&CDS_LOCATION = "R887" &SEC = "1" #&CDS_SEC = "1";
"A":   PN = "1"  !CDS_PN = "1";
"B":   PN = "2"  !CDS_PN = "2";
BODY = "Q_CAP","I107": #LOCATION = "C173" !CDS_LOCATION = "C173" &SEC = "1" #&CDS_SEC = "1";
"A":   PN = "1"  !CDS_PN = "1";
"B":   PN = "2"  !CDS_PN = "2";
DRAWING = "@scm_lib.scm(sch_1):page23";
BODY = "MOSFET_NCH_DUAL","I2": #LOCATION = "Q2" !CDS_LOCATION = "Q2" &SEC = "2" #&CDS_SEC = "2";
"D2":   PN = "3"  !CDS_PN = "3";
"G2":   PN = "5"  !CDS_PN = "5";
"S2":   PN = "4"  !CDS_PN = "4";
BODY = "Q_CAP","I11": #LOCATION = "C202" !CDS_LOCATION = "C202" &SEC = "1" #&CDS_SEC = "1";
"A":   PN = "1"  !CDS_PN = "1";
"B":   PN = "2"  !CDS_PN = "2";
BODY = "Q_CAP","I12": #LOCATION = "C203" !CDS_LOCATION = "C203" &SEC = "1" #&CDS_SEC = "1";
"A":   PN = "1"  !CDS_PN = "1";
"B":   PN = "2"  !CDS_PN = "2";
BODY = "Q_RES","I19": #LOCATION = "R18" !CDS_LOCATION = "R18" &SEC = "1" #&CDS_SEC = "1";
"A":   PN = "1"  !CDS_PN = "1";
"B":   PN = "2"  !CDS_PN = "2";
BODY = "Q_CAP","I25": #LOCATION = "C205" !CDS_LOCATION = "C205" &SEC = "1" #&CDS_SEC = "1";
"A":   PN = "1"  !CDS_PN = "1";
"B":   PN = "2"  !CDS_PN = "2";
BODY = "Q_CAP","I26": #LOCATION = "C206" !CDS_LOCATION = "C206" &SEC = "1" #&CDS_SEC = "1";
"A":   PN = "1"  !CDS_PN = "1";
"B":   PN = "2"  !CDS_PN = "2";
BODY = "Q_RES","I27": #LOCATION = "R31" !CDS_LOCATION = "R31" &SEC = "1" #&CDS_SEC = "1";
"A":   PN = "1"  !CDS_PN = "1";
"B":   PN = "2"  !CDS_PN = "2";
BODY = "Q_CAP","I29": #LOCATION = "C207" !CDS_LOCATION = "C207" &SEC = "1" #&CDS_SEC = "1";
"A":   PN = "1"  !CDS_PN = "1";
"B":   PN = "2"  !CDS_PN = "2";
BODY = "74HC1G126GW","I32": #LOCATION = "U33" !CDS_LOCATION = "U33" &SEC = "1" #&CDS_SEC = "1";
"1":   PN = "1"  !CDS_PN = "1";
"2":   PN = "2"  !CDS_PN = "2";
"4":   PN = "4"  !CDS_PN = "4";
"5":   PN = "5"  !CDS_PN = "5";
"GND":   PN = "3"  !CDS_PN = "3";
BODY = "74HC1G126GW","I33": #LOCATION = "U26" !CDS_LOCATION = "U26" &SEC = "1" #&CDS_SEC = "1";
"1":   PN = "1"  !CDS_PN = "1";
"2":   PN = "2"  !CDS_PN = "2";
"4":   PN = "4"  !CDS_PN = "4";
"5":   PN = "5"  !CDS_PN = "5";
"GND":   PN = "3"  !CDS_PN = "3";
BODY = "Q_RES","I34": #LOCATION = "R29" !CDS_LOCATION = "R29" &SEC = "1" #&CDS_SEC = "1";
"A":   PN = "1"  !CDS_PN = "1";
"B":   PN = "2"  !CDS_PN = "2";
BODY = "Q_RES","I39": #LOCATION = "R30" !CDS_LOCATION = "R30" &SEC = "1" #&CDS_SEC = "1";
"A":   PN = "1"  !CDS_PN = "1";
"B":   PN = "2"  !CDS_PN = "2";
BODY = "Q_RES","I40": #LOCATION = "R27" !CDS_LOCATION = "R27" &SEC = "1" #&CDS_SEC = "1";
"A":   PN = "1"  !CDS_PN = "1";
"B":   PN = "2"  !CDS_PN = "2";
BODY = "SCHOTTKY_AC","I41": #LOCATION = "D11" !CDS_LOCATION = "D11" &SEC = "1" #&CDS_SEC = "1";
"A":   PN = "A"  !CDS_PN = "A";
"C":   PN = "C"  !CDS_PN = "C";
BODY = "SCHOTTKY_AC","I42": #LOCATION = "D9" !CDS_LOCATION = "D9" &SEC = "1" #&CDS_SEC = "1";
"A":   PN = "A"  !CDS_PN = "A";
"C":   PN = "C"  !CDS_PN = "C";
BODY = "Q_CAP","I45": #LOCATION = "C204" !CDS_LOCATION = "C204" &SEC = "1" #&CDS_SEC = "1";
"A":   PN = "1"  !CDS_PN = "1";
"B":   PN = "2"  !CDS_PN = "2";
BODY = "Q_RES","I50": #LOCATION = "R32" !CDS_LOCATION = "R32" &SEC = "1" #&CDS_SEC = "1";
"A":   PN = "1"  !CDS_PN = "1";
"B":   PN = "2"  !CDS_PN = "2";
BODY = "Q_RES","I51": #LOCATION = "R86" !CDS_LOCATION = "R86" &SEC = "1" #&CDS_SEC = "1";
"A":   PN = "1"  !CDS_PN = "1";
"B":   PN = "2"  !CDS_PN = "2";
BODY = "Q_CAP","I54": #LOCATION = "C209" !CDS_LOCATION = "C209" &SEC = "1" #&CDS_SEC = "1";
"A":   PN = "1"  !CDS_PN = "1";
"B":   PN = "2"  !CDS_PN = "2";
BODY = "MOSFET_NCH_DUAL","I56": #LOCATION = "Q2" !CDS_LOCATION = "Q2" &SEC = "1" #&CDS_SEC = "1";
"D1":   PN = "6"  !CDS_PN = "6";
"G1":   PN = "2"  !CDS_PN = "2";
"S1":   PN = "1"  !CDS_PN = "1";
BODY = "Q_RES","I57": #LOCATION = "R87" !CDS_LOCATION = "R87" &SEC = "1" #&CDS_SEC = "1";
"A":   PN = "1"  !CDS_PN = "1";
"B":   PN = "2"  !CDS_PN = "2";
BODY = "Q_RES","I59": #LOCATION = "R88" !CDS_LOCATION = "R88" &SEC = "1" #&CDS_SEC = "1";
"A":   PN = "1"  !CDS_PN = "1";
"B":   PN = "2"  !CDS_PN = "2";
BODY = "Q_RES","I60": #LOCATION = "R85" !CDS_LOCATION = "R85" &SEC = "1" #&CDS_SEC = "1";
"A":   PN = "1"  !CDS_PN = "1";
"B":   PN = "2"  !CDS_PN = "2";
BODY = "Q_RES","I61": #LOCATION = "R84" !CDS_LOCATION = "R84" &SEC = "1" #&CDS_SEC = "1";
"A":   PN = "1"  !CDS_PN = "1";
"B":   PN = "2"  !CDS_PN = "2";
BODY = "Q_RES","I62": #LOCATION = "R91" !CDS_LOCATION = "R91" &SEC = "1" #&CDS_SEC = "1";
"A":   PN = "1"  !CDS_PN = "1";
"B":   PN = "2"  !CDS_PN = "2";
BODY = "Q_RES","I64": #LOCATION = "R92" !CDS_LOCATION = "R92" &SEC = "1" #&CDS_SEC = "1";
"A":   PN = "1"  !CDS_PN = "1";
"B":   PN = "2"  !CDS_PN = "2";
BODY = "Q_RES","I65": #LOCATION = "R89" !CDS_LOCATION = "R89" &SEC = "1" #&CDS_SEC = "1";
"A":   PN = "1"  !CDS_PN = "1";
"B":   PN = "2"  !CDS_PN = "2";
BODY = "Q_CAP","I67": #LOCATION = "C211" !CDS_LOCATION = "C211" &SEC = "1" #&CDS_SEC = "1";
"A":   PN = "1"  !CDS_PN = "1";
"B":   PN = "2"  !CDS_PN = "2";
BODY = "Q_RES","I68": #LOCATION = "R17" !CDS_LOCATION = "R17" &SEC = "1" #&CDS_SEC = "1";
"A":   PN = "1"  !CDS_PN = "1";
"B":   PN = "2"  !CDS_PN = "2";
BODY = "BZA462A","I74": #LOCATION = "D12" !CDS_LOCATION = "D12" &SEC = "1" #&CDS_SEC = "1";
"1":   PN = "1"  !CDS_PN = "1";
"2":   PN = "2"  !CDS_PN = "2";
"3":   PN = "3"  !CDS_PN = "3";
"4":   PN = "4"  !CDS_PN = "4";
"5":   PN = "5"  !CDS_PN = "5";
"6":   PN = "6"  !CDS_PN = "6";
BODY = "Q_RES","I75": #LOCATION = "R16" !CDS_LOCATION = "R16" &SEC = "1" #&CDS_SEC = "1";
"A":   PN = "1"  !CDS_PN = "1";
"B":   PN = "2"  !CDS_PN = "2";
BODY = "Q_CAP","I77": #LOCATION = "C212" !CDS_LOCATION = "C212" &SEC = "1" #&CDS_SEC = "1";
"A":   PN = "1"  !CDS_PN = "1";
"B":   PN = "2"  !CDS_PN = "2";
BODY = "Q_CAP","I83": #LOCATION = "C213" !CDS_LOCATION = "C213" &SEC = "1" #&CDS_SEC = "1";
"A":   PN = "1"  !CDS_PN = "1";
"B":   PN = "2"  !CDS_PN = "2";
BODY = "Q_CAP","I84": #LOCATION = "C214" !CDS_LOCATION = "C214" &SEC = "1" #&CDS_SEC = "1";
"A":   PN = "1"  !CDS_PN = "1";
"B":   PN = "2"  !CDS_PN = "2";
BODY = "Q_RES","I99": #LOCATION = "R28" !CDS_LOCATION = "R28" &SEC = "1" #&CDS_SEC = "1";
"A":   PN = "1"  !CDS_PN = "1";
"B":   PN = "2"  !CDS_PN = "2";
BODY = "Q_FUSE","I153": #LOCATION = "FS1" !CDS_LOCATION = "FS1" #SEC = "1" !CDS_SEC = "1";
"1":   PN = "1"  !CDS_PN = "1";
"2":   PN = "2"  !CDS_PN = "2";
BODY = "DT1240E04LP7","I155": #LOCATION = "U35" !CDS_LOCATION = "U35" &SEC = "1" #&CDS_SEC = "1";
"IO1":   PN = "1"  !CDS_PN = "1";
"IO2":   PN = "2"  !CDS_PN = "2";
"IO3":   PN = "4"  !CDS_PN = "4";
"IO4":   PN = "5"  !CDS_PN = "5";
"NC1":   PN = "6"  !CDS_PN = "6";
"NC2":   PN = "7"  !CDS_PN = "7";
"NC3":   PN = "9"  !CDS_PN = "9";
"NC4":   PN = "10"  !CDS_PN = "10";
"VSS1":   PN = "3"  !CDS_PN = "3";
"VSS2":   PN = "8"  !CDS_PN = "8";
BODY = "DT1240E04LP7","I156": #LOCATION = "U34" !CDS_LOCATION = "U34" &SEC = "1" #&CDS_SEC = "1";
"IO1":   PN = "1"  !CDS_PN = "1";
"IO2":   PN = "2"  !CDS_PN = "2";
"IO3":   PN = "4"  !CDS_PN = "4";
"IO4":   PN = "5"  !CDS_PN = "5";
"NC1":   PN = "6"  !CDS_PN = "6";
"NC2":   PN = "7"  !CDS_PN = "7";
"NC3":   PN = "9"  !CDS_PN = "9";
"NC4":   PN = "10"  !CDS_PN = "10";
"VSS1":   PN = "3"  !CDS_PN = "3";
"VSS2":   PN = "8"  !CDS_PN = "8";
BODY = "SCHOTTKY_12","I161": #LOCATION = "D16" !CDS_LOCATION = "D16" &SEC = "1" #&CDS_SEC = "1";
"A":   PN = "1"  !CDS_PN = "1";
"C":   PN = "2"  !CDS_PN = "2";
BODY = "SCONN13_502280130CV01","I165": #LOCATION = "J8" !CDS_LOCATION = "J8" &SEC = "1" #&CDS_SEC = "1";
"1":   PN = "1"  !CDS_PN = "1";
"2":   PN = "2"  !CDS_PN = "2";
"3":   PN = "3"  !CDS_PN = "3";
"4":   PN = "4"  !CDS_PN = "4";
"5":   PN = "5"  !CDS_PN = "5";
"6":   PN = "6"  !CDS_PN = "6";
"7":   PN = "7"  !CDS_PN = "7";
"8":   PN = "8"  !CDS_PN = "8";
"9":   PN = "9"  !CDS_PN = "9";
"10":   PN = "10"  !CDS_PN = "10";
"11":   PN = "11"  !CDS_PN = "11";
"12":   PN = "12"  !CDS_PN = "12";
"13":   PN = "13"  !CDS_PN = "13";
"G1":   PN = "G1"  !CDS_PN = "G1";
"G2":   PN = "G2"  !CDS_PN = "G2";
BODY = "Q_INDUCTOR","I166": #LOCATION = "L28" !CDS_LOCATION = "L28" &SEC = "1" #&CDS_SEC = "1";
"1":   PN = "1"  !CDS_PN = "1";
"2":   PN = "2"  !CDS_PN = "2";
BODY = "Q_INDUCTOR","I167": #LOCATION = "L29" !CDS_LOCATION = "L29" &SEC = "1" #&CDS_SEC = "1";
"1":   PN = "1"  !CDS_PN = "1";
"2":   PN = "2"  !CDS_PN = "2";
BODY = "Q_INDUCTOR","I168": #LOCATION = "L30" !CDS_LOCATION = "L30" &SEC = "1" #&CDS_SEC = "1";
"1":   PN = "1"  !CDS_PN = "1";
"2":   PN = "2"  !CDS_PN = "2";
BODY = "Q_CAP","I169": #LOCATION = "C208" !CDS_LOCATION = "C208" &SEC = "1" #&CDS_SEC = "1";
"A":   PN = "1"  !CDS_PN = "1";
"B":   PN = "2"  !CDS_PN = "2";
BODY = "Q_CAP","I170": #LOCATION = "C210" !CDS_LOCATION = "C210" &SEC = "1" #&CDS_SEC = "1";
"A":   PN = "1"  !CDS_PN = "1";
"B":   PN = "2"  !CDS_PN = "2";
DRAWING = "@scm_lib.scm(sch_1):page25";
BODY = "Q_RES","I3": #LOCATION = "R563" !CDS_LOCATION = "R563" &SEC = "1" #&CDS_SEC = "1";
"A":   PN = "1"  !CDS_PN = "1";
"B":   PN = "2"  !CDS_PN = "2";
BODY = "SN74LVC1G07DCKR","I61": #LOCATION = "U44" !CDS_LOCATION = "U44" &SEC = "1" #&CDS_SEC = "1";
"A":   PN = "2"  !CDS_PN = "2";
"GND":   PN = "3"  !CDS_PN = "3";
"NC1":   PN = "1"  !CDS_PN = "1";
"VCC":   PN = "5"  !CDS_PN = "5";
"Y":   PN = "4"  !CDS_PN = "4";
BODY = "Q_CAP","I65": #LOCATION = "C304" !CDS_LOCATION = "C304" #SEC = "1" !CDS_SEC = "1";
"A":   PN = "1"  !CDS_PN = "1";
"B":   PN = "2"  !CDS_PN = "2";
BODY = "Q_RES","I67": #LOCATION = "R752" !CDS_LOCATION = "R752" &SEC = "1" #&CDS_SEC = "1";
"A":   PN = "1"  !CDS_PN = "1";
"B":   PN = "2"  !CDS_PN = "2";
BODY = "Q_RES","I73": #LOCATION = "R827" !CDS_LOCATION = "R827" &SEC = "1" #&CDS_SEC = "1";
"A":   PN = "1"  !CDS_PN = "1";
"B":   PN = "2"  !CDS_PN = "2";
BODY = "74LVC1G74DP","I138": LOCATION = "U54" #&CDS_LOCATION = "U54" &SEC = "1" #&CDS_SEC = "1";
"CP":   PN = "1"  !CDS_PN = "1";
"D":   PN = "2"  !CDS_PN = "2";
"GND":   PN = "4"  !CDS_PN = "4";
"Q":   PN = "5"  !CDS_PN = "5";
"Q_N":   PN = "3"  !CDS_PN = "3";
"RD_N":   PN = "6"  !CDS_PN = "6";
"SD_N":   PN = "7"  !CDS_PN = "7";
"VCC":   PN = "8"  !CDS_PN = "8";
BODY = "Q_RES","I142": LOCATION = "R182" #&CDS_LOCATION = "R182" &SEC = "1" #&CDS_SEC = "1";
"A":   PN = "1"  !CDS_PN = "1";
"B":   PN = "2"  !CDS_PN = "2";
BODY = "Q_RES","I143": LOCATION = "R545" #&CDS_LOCATION = "R545" &SEC = "1" #&CDS_SEC = "1";
"A":   PN = "1"  !CDS_PN = "1";
"B":   PN = "2"  !CDS_PN = "2";
BODY = "Q_CAP","I146": LOCATION = "C312" #&CDS_LOCATION = "C312" &SEC = "1" #&CDS_SEC = "1";
"A":   PN = "1"  !CDS_PN = "1";
"B":   PN = "2"  !CDS_PN = "2";
BODY = "Q_RES","I149": LOCATION = "R560" #&CDS_LOCATION = "R560" &SEC = "1" #&CDS_SEC = "1";
"A":   PN = "1"  !CDS_PN = "1";
"B":   PN = "2"  !CDS_PN = "2";
BODY = "SN74LVC1G14DCKR","I150": LOCATION = "U55" #&CDS_LOCATION = "U55" &SEC = "1" #&CDS_SEC = "1";
"A":   PN = "2"  !CDS_PN = "2";
"GND":   PN = "3"  !CDS_PN = "3";
"NC":   PN = "1"  !CDS_PN = "1";
"VCC":   PN = "5"  !CDS_PN = "5";
"Y":   PN = "4"  !CDS_PN = "4";
BODY = "Q_CAP","I154": LOCATION = "C313" #&CDS_LOCATION = "C313" &SEC = "1" #&CDS_SEC = "1";
"A":   PN = "1"  !CDS_PN = "1";
"B":   PN = "2"  !CDS_PN = "2";
BODY = "Q_RES","I156": LOCATION = "R554" #&CDS_LOCATION = "R554" &SEC = "1" #&CDS_SEC = "1";
"A":   PN = "1"  !CDS_PN = "1";
"B":   PN = "2"  !CDS_PN = "2";
BODY = "SCONN3_212H9103GBR1","I169": #LOCATION = "J1" !CDS_LOCATION = "J1" &SEC = "1" #&CDS_SEC = "1";
"1":   PN = "1"  !CDS_PN = "1";
"2":   PN = "2"  !CDS_PN = "2";
"3":   PN = "3"  !CDS_PN = "3";
BODY = "Q_RES","I170": #LOCATION = "R181" !CDS_LOCATION = "R181" &SEC = "1" #&CDS_SEC = "1";
"A":   PN = "1"  !CDS_PN = "1";
"B":   PN = "2"  !CDS_PN = "2";
BODY = "Q_RES","I171": #LOCATION = "R592" !CDS_LOCATION = "R592" &SEC = "1" #&CDS_SEC = "1";
"A":   PN = "1"  !CDS_PN = "1";
"B":   PN = "2"  !CDS_PN = "2";
BODY = "Q_RES","I172": #LOCATION = "R548" !CDS_LOCATION = "R548" &SEC = "1" #&CDS_SEC = "1";
"A":   PN = "1"  !CDS_PN = "1";
"B":   PN = "2"  !CDS_PN = "2";
BODY = "Q_RES","I173": #LOCATION = "R551" !CDS_LOCATION = "R551" &SEC = "1" #&CDS_SEC = "1";
"A":   PN = "1"  !CDS_PN = "1";
"B":   PN = "2"  !CDS_PN = "2";
BODY = "Q_RES","I174": #LOCATION = "R555" !CDS_LOCATION = "R555" &SEC = "1" #&CDS_SEC = "1";
"A":   PN = "1"  !CDS_PN = "1";
"B":   PN = "2"  !CDS_PN = "2";
BODY = "Q_RES","I175": #LOCATION = "R556" !CDS_LOCATION = "R556" &SEC = "1" #&CDS_SEC = "1";
"A":   PN = "1"  !CDS_PN = "1";
"B":   PN = "2"  !CDS_PN = "2";
BODY = "Q_RES","I176": #LOCATION = "R559" !CDS_LOCATION = "R559" &SEC = "1" #&CDS_SEC = "1";
"A":   PN = "1"  !CDS_PN = "1";
"B":   PN = "2"  !CDS_PN = "2";
DRAWING = "@scm_lib.scm(sch_1):page26";
BODY = "Q_RES","I6": #LOCATION = "R411" !CDS_LOCATION = "R411" &SEC = "1" #&CDS_SEC = "1";
"A":   PN = "1"  !CDS_PN = "1";
"B":   PN = "2"  !CDS_PN = "2";
BODY = "Q_RES","I8": #LOCATION = "R412" !CDS_LOCATION = "R412" &SEC = "1" #&CDS_SEC = "1";
"A":   PN = "1"  !CDS_PN = "1";
"B":   PN = "2"  !CDS_PN = "2";
BODY = "Q_RES","I9": #LOCATION = "R12" !CDS_LOCATION = "R12" #SEC = "1" !CDS_SEC = "1";
"A":   PN = "1"  !CDS_PN = "1";
"B":   PN = "2"  !CDS_PN = "2";
BODY = "Q_RES","I11": #LOCATION = "R13" !CDS_LOCATION = "R13" #SEC = "1" !CDS_SEC = "1";
"A":   PN = "1"  !CDS_PN = "1";
"B":   PN = "2"  !CDS_PN = "2";
BODY = "Q_RES","I12": #LOCATION = "R413" !CDS_LOCATION = "R413" &SEC = "1" #&CDS_SEC = "1";
"A":   PN = "1"  !CDS_PN = "1";
"B":   PN = "2"  !CDS_PN = "2";
BODY = "Q_RES","I14": #LOCATION = "R14" !CDS_LOCATION = "R14" #SEC = "1" !CDS_SEC = "1";
"A":   PN = "1"  !CDS_PN = "1";
"B":   PN = "2"  !CDS_PN = "2";
BODY = "M24128BWDW6TP","I15": #LOCATION = "U19" !CDS_LOCATION = "U19" &SEC = "1" #&CDS_SEC = "1";
"E0":   PN = "1"  !CDS_PN = "1";
"E1":   PN = "2"  !CDS_PN = "2";
"E2":   PN = "3"  !CDS_PN = "3";
"SCL":   PN = "6"  !CDS_PN = "6";
"SDA":   PN = "5"  !CDS_PN = "5";
"VCC":   PN = "8"  !CDS_PN = "8";
"VSS":   PN = "4"  !CDS_PN = "4";
"WC#":   PN = "7"  !CDS_PN = "7";
BODY = "Q_CAP","I17": #LOCATION = "C192" !CDS_LOCATION = "C192" &SEC = "1" #&CDS_SEC = "1";
"A":   PN = "1"  !CDS_PN = "1";
"B":   PN = "2"  !CDS_PN = "2";
BODY = "Q_RES","I32": #LOCATION = "R15" !CDS_LOCATION = "R15" &SEC = "1" #&CDS_SEC = "1";
"A":   PN = "1"  !CDS_PN = "1";
"B":   PN = "2"  !CDS_PN = "2";
BODY = "Q_RES","I33": #LOCATION = "R421" !CDS_LOCATION = "R421" &SEC = "1" #&CDS_SEC = "1";
"A":   PN = "1"  !CDS_PN = "1";
"B":   PN = "2"  !CDS_PN = "2";
BODY = "Q_RES","I37": #LOCATION = "R419" !CDS_LOCATION = "R419" #SEC = "1" !CDS_SEC = "1";
"A":   PN = "1"  !CDS_PN = "1";
"B":   PN = "2"  !CDS_PN = "2";
BODY = "Q_RES","I39": #LOCATION = "R417" !CDS_LOCATION = "R417" #SEC = "1" !CDS_SEC = "1";
"A":   PN = "1"  !CDS_PN = "1";
"B":   PN = "2"  !CDS_PN = "2";
BODY = "Q_RES","I40": #LOCATION = "R418" !CDS_LOCATION = "R418" &SEC = "1" #&CDS_SEC = "1";
"A":   PN = "1"  !CDS_PN = "1";
"B":   PN = "2"  !CDS_PN = "2";
BODY = "Q_RES","I41": #LOCATION = "R416" !CDS_LOCATION = "R416" &SEC = "1" #&CDS_SEC = "1";
"A":   PN = "1"  !CDS_PN = "1";
"B":   PN = "2"  !CDS_PN = "2";
BODY = "Q_CAP","I54": #LOCATION = "C191" !CDS_LOCATION = "C191" &SEC = "1" #&CDS_SEC = "1";
"A":   PN = "1"  !CDS_PN = "1";
"B":   PN = "2"  !CDS_PN = "2";
BODY = "Q_RES","I56": #LOCATION = "R410" !CDS_LOCATION = "R410" &SEC = "1" #&CDS_SEC = "1";
"A":   PN = "1"  !CDS_PN = "1";
"B":   PN = "2"  !CDS_PN = "2";
BODY = "Q_RES","I57": #LOCATION = "R409" !CDS_LOCATION = "R409" &SEC = "1" #&CDS_SEC = "1";
"A":   PN = "1"  !CDS_PN = "1";
"B":   PN = "2"  !CDS_PN = "2";
BODY = "Q_RES","I65": LOCATION = "R54" #&CDS_LOCATION = "R54" &SEC = "1" #&CDS_SEC = "1";
"A":   PN = "1"  !CDS_PN = "1";
"B":   PN = "2"  !CDS_PN = "2";
BODY = "Q_RES","I66": LOCATION = "R53" #&CDS_LOCATION = "R53" &SEC = "1" #&CDS_SEC = "1";
"A":   PN = "1"  !CDS_PN = "1";
"B":   PN = "2"  !CDS_PN = "2";
BODY = "Q_RES","I67": LOCATION = "R52" #&CDS_LOCATION = "R52" &SEC = "1" #&CDS_SEC = "1";
"A":   PN = "1"  !CDS_PN = "1";
"B":   PN = "2"  !CDS_PN = "2";
BODY = "Q_RES","I69": #LOCATION = "R420" !CDS_LOCATION = "R420" &SEC = "1" #&CDS_SEC = "1";
"A":   PN = "1"  !CDS_PN = "1";
"B":   PN = "2"  !CDS_PN = "2";
BODY = "CONN8_TSW10407FD","I71": #LOCATION = "J14" !CDS_LOCATION = "J14" &SEC = "1" #&CDS_SEC = "1";
"1":   PN = "1"  !CDS_PN = "1";
"2":   PN = "2"  !CDS_PN = "2";
"3":   PN = "3"  !CDS_PN = "3";
"4":   PN = "4"  !CDS_PN = "4";
"5":   PN = "5"  !CDS_PN = "5";
"6":   PN = "6"  !CDS_PN = "6";
"7":   PN = "7"  !CDS_PN = "7";
"8":   PN = "8"  !CDS_PN = "8";
DRAWING = "@scm_lib.scm(sch_1):page27";
BODY = "Q_RES","I84": #LOCATION = "R269" !CDS_LOCATION = "R269" &SEC = "1" #&CDS_SEC = "1";
"A":   PN = "1"  !CDS_PN = "1";
"B":   PN = "2"  !CDS_PN = "2";
BODY = "Q_RES","I85": #LOCATION = "R267" !CDS_LOCATION = "R267" &SEC = "1" #&CDS_SEC = "1";
"A":   PN = "1"  !CDS_PN = "1";
"B":   PN = "2"  !CDS_PN = "2";
BODY = "Q_RES","I86": #LOCATION = "R268" !CDS_LOCATION = "R268" &SEC = "1" #&CDS_SEC = "1";
"A":   PN = "1"  !CDS_PN = "1";
"B":   PN = "2"  !CDS_PN = "2";
BODY = "Q_RES","I88": #LOCATION = "R265" !CDS_LOCATION = "R265" &SEC = "1" #&CDS_SEC = "1";
"A":   PN = "1"  !CDS_PN = "1";
"B":   PN = "2"  !CDS_PN = "2";
BODY = "Q_RES","I89": #LOCATION = "R264" !CDS_LOCATION = "R264" &SEC = "1" #&CDS_SEC = "1";
"A":   PN = "1"  !CDS_PN = "1";
"B":   PN = "2"  !CDS_PN = "2";
BODY = "Q_RES","I93": #LOCATION = "R262" !CDS_LOCATION = "R262" &SEC = "1" #&CDS_SEC = "1";
"A":   PN = "1"  !CDS_PN = "1";
"B":   PN = "2"  !CDS_PN = "2";
BODY = "Q_RES","I94": #LOCATION = "R261" !CDS_LOCATION = "R261" &SEC = "1" #&CDS_SEC = "1";
"A":   PN = "1"  !CDS_PN = "1";
"B":   PN = "2"  !CDS_PN = "2";
BODY = "Q_RES","I95": #LOCATION = "R266" !CDS_LOCATION = "R266" &SEC = "1" #&CDS_SEC = "1";
"A":   PN = "1"  !CDS_PN = "1";
"B":   PN = "2"  !CDS_PN = "2";
BODY = "Q_RES","I96": #LOCATION = "R259" !CDS_LOCATION = "R259" &SEC = "1" #&CDS_SEC = "1";
"A":   PN = "1"  !CDS_PN = "1";
"B":   PN = "2"  !CDS_PN = "2";
BODY = "Q_RES","I97": #LOCATION = "R260" !CDS_LOCATION = "R260" &SEC = "1" #&CDS_SEC = "1";
"A":   PN = "1"  !CDS_PN = "1";
"B":   PN = "2"  !CDS_PN = "2";
BODY = "Q_RES","I98": #LOCATION = "R258" !CDS_LOCATION = "R258" &SEC = "1" #&CDS_SEC = "1";
"A":   PN = "1"  !CDS_PN = "1";
"B":   PN = "2"  !CDS_PN = "2";
BODY = "Q_RES","I99": #LOCATION = "R257" !CDS_LOCATION = "R257" &SEC = "1" #&CDS_SEC = "1";
"A":   PN = "1"  !CDS_PN = "1";
"B":   PN = "2"  !CDS_PN = "2";
BODY = "Q_RES","I100": #LOCATION = "R256" !CDS_LOCATION = "R256" &SEC = "1" #&CDS_SEC = "1";
"A":   PN = "1"  !CDS_PN = "1";
"B":   PN = "2"  !CDS_PN = "2";
BODY = "Q_RES","I101": #LOCATION = "R254" !CDS_LOCATION = "R254" &SEC = "1" #&CDS_SEC = "1";
"A":   PN = "1"  !CDS_PN = "1";
"B":   PN = "2"  !CDS_PN = "2";
BODY = "Q_RES","I102": #LOCATION = "R255" !CDS_LOCATION = "R255" &SEC = "1" #&CDS_SEC = "1";
"A":   PN = "1"  !CDS_PN = "1";
"B":   PN = "2"  !CDS_PN = "2";
BODY = "Q_RES","I103": #LOCATION = "R253" !CDS_LOCATION = "R253" &SEC = "1" #&CDS_SEC = "1";
"A":   PN = "1"  !CDS_PN = "1";
"B":   PN = "2"  !CDS_PN = "2";
BODY = "Q_RES","I105": #LOCATION = "R252" !CDS_LOCATION = "R252" &SEC = "1" #&CDS_SEC = "1";
"A":   PN = "1"  !CDS_PN = "1";
"B":   PN = "2"  !CDS_PN = "2";
BODY = "Q_RES","I106": #LOCATION = "R250" !CDS_LOCATION = "R250" &SEC = "1" #&CDS_SEC = "1";
"A":   PN = "1"  !CDS_PN = "1";
"B":   PN = "2"  !CDS_PN = "2";
BODY = "Q_RES","I107": #LOCATION = "R248" !CDS_LOCATION = "R248" &SEC = "1" #&CDS_SEC = "1";
"A":   PN = "1"  !CDS_PN = "1";
"B":   PN = "2"  !CDS_PN = "2";
BODY = "Q_RES","I108": #LOCATION = "R249" !CDS_LOCATION = "R249" &SEC = "1" #&CDS_SEC = "1";
"A":   PN = "1"  !CDS_PN = "1";
"B":   PN = "2"  !CDS_PN = "2";
BODY = "Q_RES","I109": #LOCATION = "R247" !CDS_LOCATION = "R247" &SEC = "1" #&CDS_SEC = "1";
"A":   PN = "1"  !CDS_PN = "1";
"B":   PN = "2"  !CDS_PN = "2";
BODY = "Q_RES","I145": #LOCATION = "R246" !CDS_LOCATION = "R246" &SEC = "1" #&CDS_SEC = "1";
"A":   PN = "1"  !CDS_PN = "1";
"B":   PN = "2"  !CDS_PN = "2";
BODY = "Q_RES","I146": #LOCATION = "R245" !CDS_LOCATION = "R245" &SEC = "1" #&CDS_SEC = "1";
"A":   PN = "1"  !CDS_PN = "1";
"B":   PN = "2"  !CDS_PN = "2";
BODY = "Q_RES","I147": #LOCATION = "R244" !CDS_LOCATION = "R244" &SEC = "1" #&CDS_SEC = "1";
"A":   PN = "1"  !CDS_PN = "1";
"B":   PN = "2"  !CDS_PN = "2";
BODY = "Q_RES","I163": #LOCATION = "R699" !CDS_LOCATION = "R699" &SEC = "1" #&CDS_SEC = "1";
"A":   PN = "1"  !CDS_PN = "1";
"B":   PN = "2"  !CDS_PN = "2";
BODY = "Q_RES","I165": #LOCATION = "R714" !CDS_LOCATION = "R714" &SEC = "1" #&CDS_SEC = "1";
"A":   PN = "1"  !CDS_PN = "1";
"B":   PN = "2"  !CDS_PN = "2";
BODY = "Q_CAP","I166": #LOCATION = "C267" !CDS_LOCATION = "C267" &SEC = "1" #&CDS_SEC = "1";
"A":   PN = "1"  !CDS_PN = "1";
"B":   PN = "2"  !CDS_PN = "2";
BODY = "Q_RES","I168": #LOCATION = "R842" !CDS_LOCATION = "R842" &SEC = "1" #&CDS_SEC = "1";
"A":   PN = "1"  !CDS_PN = "1";
"B":   PN = "2"  !CDS_PN = "2";
BODY = "Q_RES","I177": #LOCATION = "R843" !CDS_LOCATION = "R843" &SEC = "1" #&CDS_SEC = "1";
"A":   PN = "1"  !CDS_PN = "1";
"B":   PN = "2"  !CDS_PN = "2";
BODY = "Q_RES","I179": #LOCATION = "R844" !CDS_LOCATION = "R844" &SEC = "1" #&CDS_SEC = "1";
"A":   PN = "1"  !CDS_PN = "1";
"B":   PN = "2"  !CDS_PN = "2";
BODY = "Q_RES","I181": #LOCATION = "R846" !CDS_LOCATION = "R846" &SEC = "1" #&CDS_SEC = "1";
"A":   PN = "1"  !CDS_PN = "1";
"B":   PN = "2"  !CDS_PN = "2";
BODY = "Q_RES","I182": #LOCATION = "R848" !CDS_LOCATION = "R848" &SEC = "1" #&CDS_SEC = "1";
"A":   PN = "1"  !CDS_PN = "1";
"B":   PN = "2"  !CDS_PN = "2";
BODY = "Q_RES","I184": #LOCATION = "R851" !CDS_LOCATION = "R851" &SEC = "1" #&CDS_SEC = "1";
"A":   PN = "1"  !CDS_PN = "1";
"B":   PN = "2"  !CDS_PN = "2";
BODY = "BAT54C","I185": #LOCATION = "U11" !CDS_LOCATION = "U11" &SEC = "1" #&CDS_SEC = "1";
"A":   PN = "2"  !CDS_PN = "2";
"B":   PN = "1"  !CDS_PN = "1";
"C":   PN = "3"  !CDS_PN = "3";
BODY = "Q_RES","I188": #LOCATION = "R430" !CDS_LOCATION = "R430" &SEC = "1" #&CDS_SEC = "1";
"A":   PN = "1"  !CDS_PN = "1";
"B":   PN = "2"  !CDS_PN = "2";
BODY = "Q_RES","I213": #LOCATION = "R754" !CDS_LOCATION = "R754" &SEC = "1" #&CDS_SEC = "1";
"A":   PN = "1"  !CDS_PN = "1";
"B":   PN = "2"  !CDS_PN = "2";
BODY = "Q_RES","I217": #LOCATION = "R770" !CDS_LOCATION = "R770" &SEC = "1" #&CDS_SEC = "1";
"A":   PN = "1"  !CDS_PN = "1";
"B":   PN = "2"  !CDS_PN = "2";
BODY = "Q_RES","I222": #LOCATION = "R42" !CDS_LOCATION = "R42" &SEC = "1" #&CDS_SEC = "1";
"A":   PN = "1"  !CDS_PN = "1";
"B":   PN = "2"  !CDS_PN = "2";
BODY = "Q_RES","I228": #LOCATION = "R140" !CDS_LOCATION = "R140" &SEC = "1" #&CDS_SEC = "1";
"A":   PN = "1"  !CDS_PN = "1";
"B":   PN = "2"  !CDS_PN = "2";
BODY = "Q_RES","I233": #LOCATION = "R753" !CDS_LOCATION = "R753" &SEC = "1" #&CDS_SEC = "1";
"A":   PN = "1"  !CDS_PN = "1";
"B":   PN = "2"  !CDS_PN = "2";
BODY = "Q_RES","I234": #LOCATION = "R521" !CDS_LOCATION = "R521" &SEC = "1" #&CDS_SEC = "1";
"A":   PN = "1"  !CDS_PN = "1";
"B":   PN = "2"  !CDS_PN = "2";
BODY = "Q_RES","I235": #LOCATION = "R145" !CDS_LOCATION = "R145" &SEC = "1" #&CDS_SEC = "1";
"A":   PN = "1"  !CDS_PN = "1";
"B":   PN = "2"  !CDS_PN = "2";
BODY = "Q_RES","I236": #LOCATION = "R149" !CDS_LOCATION = "R149" &SEC = "1" #&CDS_SEC = "1";
"A":   PN = "1"  !CDS_PN = "1";
"B":   PN = "2"  !CDS_PN = "2";
BODY = "Q_RES","I237": #LOCATION = "R610" !CDS_LOCATION = "R610" &SEC = "1" #&CDS_SEC = "1";
"A":   PN = "1"  !CDS_PN = "1";
"B":   PN = "2"  !CDS_PN = "2";
BODY = "Q_RES","I238": #LOCATION = "R692" !CDS_LOCATION = "R692" &SEC = "1" #&CDS_SEC = "1";
"A":   PN = "1"  !CDS_PN = "1";
"B":   PN = "2"  !CDS_PN = "2";
BODY = "Q_RES","I239": #LOCATION = "R422" !CDS_LOCATION = "R422" &SEC = "1" #&CDS_SEC = "1";
"A":   PN = "1"  !CDS_PN = "1";
"B":   PN = "2"  !CDS_PN = "2";
BODY = "Q_RES","I240": #LOCATION = "R428" !CDS_LOCATION = "R428" &SEC = "1" #&CDS_SEC = "1";
"A":   PN = "1"  !CDS_PN = "1";
"B":   PN = "2"  !CDS_PN = "2";
BODY = "Q_RES","I241": #LOCATION = "R429" !CDS_LOCATION = "R429" &SEC = "1" #&CDS_SEC = "1";
"A":   PN = "1"  !CDS_PN = "1";
"B":   PN = "2"  !CDS_PN = "2";
BODY = "Q_RES","I242": #LOCATION = "R438" !CDS_LOCATION = "R438" &SEC = "1" #&CDS_SEC = "1";
"A":   PN = "1"  !CDS_PN = "1";
"B":   PN = "2"  !CDS_PN = "2";
BODY = "2N7002A7","I243": #LOCATION = "Q7" !CDS_LOCATION = "Q7" &SEC = "1" #&CDS_SEC = "1";
"D":   PN = "D"  !CDS_PN = "D";
"G":   PN = "G"  !CDS_PN = "G";
"S":   PN = "S"  !CDS_PN = "S";
BODY = "Q_RES","I244": LOCATION = "R164" #&CDS_LOCATION = "R164" &SEC = "1" #&CDS_SEC = "1";
"A":   PN = "1"  !CDS_PN = "1";
"B":   PN = "2"  !CDS_PN = "2";
BODY = "Q_RES","I246": #LOCATION = "R94" !CDS_LOCATION = "R94" &SEC = "1" #&CDS_SEC = "1";
"A":   PN = "1"  !CDS_PN = "1";
"B":   PN = "2"  !CDS_PN = "2";
BODY = "Q_RES","I247": #LOCATION = "R251" !CDS_LOCATION = "R251" &SEC = "1" #&CDS_SEC = "1";
"A":   PN = "1"  !CDS_PN = "1";
"B":   PN = "2"  !CDS_PN = "2";
DRAWING = "@scm_lib.scm(sch_1):page28";
BODY = "Q_CAP","I35": #LOCATION = "C172" !CDS_LOCATION = "C172" &SEC = "1" #&CDS_SEC = "1";
"A":   PN = "1"  !CDS_PN = "1";
"B":   PN = "2"  !CDS_PN = "2";
BODY = "Q_CAP","I38": #LOCATION = "C171" !CDS_LOCATION = "C171" &SEC = "1" #&CDS_SEC = "1";
"A":   PN = "1"  !CDS_PN = "1";
"B":   PN = "2"  !CDS_PN = "2";
BODY = "Q_RES","I42": #LOCATION = "R383" !CDS_LOCATION = "R383" &SEC = "1" #&CDS_SEC = "1";
"A":   PN = "1"  !CDS_PN = "1";
"B":   PN = "2"  !CDS_PN = "2";
BODY = "Q_RES","I54": #LOCATION = "R378" !CDS_LOCATION = "R378" &SEC = "1" #&CDS_SEC = "1";
"A":   PN = "1"  !CDS_PN = "1";
"B":   PN = "2"  !CDS_PN = "2";
BODY = "Q_RES","I62": #LOCATION = "R376" !CDS_LOCATION = "R376" &SEC = "1" #&CDS_SEC = "1";
"A":   PN = "1"  !CDS_PN = "1";
"B":   PN = "2"  !CDS_PN = "2";
BODY = "Q_RES","I63": #LOCATION = "R377" !CDS_LOCATION = "R377" &SEC = "1" #&CDS_SEC = "1";
"A":   PN = "1"  !CDS_PN = "1";
"B":   PN = "2"  !CDS_PN = "2";
BODY = "Q_RES","I91": #LOCATION = "R299" !CDS_LOCATION = "R299" &SEC = "1" #&CDS_SEC = "1";
"A":   PN = "1"  !CDS_PN = "1";
"B":   PN = "2"  !CDS_PN = "2";
BODY = "Q_RES","I96": #LOCATION = "R298" !CDS_LOCATION = "R298" &SEC = "1" #&CDS_SEC = "1";
"A":   PN = "1"  !CDS_PN = "1";
"B":   PN = "2"  !CDS_PN = "2";
BODY = "Q_CAP","I98": #LOCATION = "C159" !CDS_LOCATION = "C159" &SEC = "1" #&CDS_SEC = "1";
"A":   PN = "1"  !CDS_PN = "1";
"B":   PN = "2"  !CDS_PN = "2";
BODY = "PCA9517ADP","I99": #LOCATION = "U37" !CDS_LOCATION = "U37" &SEC = "1" #&CDS_SEC = "1";
"ENABLE":   PN = "5"  !CDS_PN = "5";
"GND":   PN = "4"  !CDS_PN = "4";
"SCLA":   PN = "2"  !CDS_PN = "2";
"SCLB":   PN = "7"  !CDS_PN = "7";
"SDAA":   PN = "3"  !CDS_PN = "3";
"SDAB":   PN = "6"  !CDS_PN = "6";
"VCCA":   PN = "1"  !CDS_PN = "1";
"VCCB":   PN = "8"  !CDS_PN = "8";
BODY = "Q_CAP","I101": #LOCATION = "C158" !CDS_LOCATION = "C158" &SEC = "1" #&CDS_SEC = "1";
"A":   PN = "1"  !CDS_PN = "1";
"B":   PN = "2"  !CDS_PN = "2";
BODY = "Q_RES","I104": #LOCATION = "R670" !CDS_LOCATION = "R670" &SEC = "1" #&CDS_SEC = "1";
"A":   PN = "1"  !CDS_PN = "1";
"B":   PN = "2"  !CDS_PN = "2";
BODY = "Q_RES","I105": #LOCATION = "R296" !CDS_LOCATION = "R296" &SEC = "1" #&CDS_SEC = "1";
"A":   PN = "1"  !CDS_PN = "1";
"B":   PN = "2"  !CDS_PN = "2";
BODY = "Q_RES","I108": #LOCATION = "R294" !CDS_LOCATION = "R294" &SEC = "1" #&CDS_SEC = "1";
"A":   PN = "1"  !CDS_PN = "1";
"B":   PN = "2"  !CDS_PN = "2";
BODY = "Q_RES","I109": #LOCATION = "R135" !CDS_LOCATION = "R135" &SEC = "1" #&CDS_SEC = "1";
"A":   PN = "1"  !CDS_PN = "1";
"B":   PN = "2"  !CDS_PN = "2";
BODY = "Q_RES","I113": #LOCATION = "R295" !CDS_LOCATION = "R295" &SEC = "1" #&CDS_SEC = "1";
"A":   PN = "1"  !CDS_PN = "1";
"B":   PN = "2"  !CDS_PN = "2";
BODY = "Q_RES","I125": #LOCATION = "R701" !CDS_LOCATION = "R701" &SEC = "1" #&CDS_SEC = "1";
"A":   PN = "1"  !CDS_PN = "1";
"B":   PN = "2"  !CDS_PN = "2";
BODY = "Q_RES","I126": #LOCATION = "R702" !CDS_LOCATION = "R702" &SEC = "1" #&CDS_SEC = "1";
"A":   PN = "1"  !CDS_PN = "1";
"B":   PN = "2"  !CDS_PN = "2";
BODY = "Q_RES","I127": #LOCATION = "R703" !CDS_LOCATION = "R703" &SEC = "1" #&CDS_SEC = "1";
"A":   PN = "1"  !CDS_PN = "1";
"B":   PN = "2"  !CDS_PN = "2";
BODY = "Q_RES","I128": #LOCATION = "R719" !CDS_LOCATION = "R719" &SEC = "1" #&CDS_SEC = "1";
"A":   PN = "1"  !CDS_PN = "1";
"B":   PN = "2"  !CDS_PN = "2";
BODY = "PCA9555PW","I141": #LOCATION = "U40" !CDS_LOCATION = "U40" #SEC = "1" !CDS_SEC = "1";
"A0":   PN = "21"  !CDS_PN = "21";
"A1":   PN = "2"  !CDS_PN = "2";
"A2":   PN = "3"  !CDS_PN = "3";
"INT*":   PN = "1"  !CDS_PN = "1";
"P00":   PN = "4"  !CDS_PN = "4";
"P01":   PN = "5"  !CDS_PN = "5";
"P02":   PN = "6"  !CDS_PN = "6";
"P03":   PN = "7"  !CDS_PN = "7";
"P04":   PN = "8"  !CDS_PN = "8";
"P05":   PN = "9"  !CDS_PN = "9";
"P06":   PN = "10"  !CDS_PN = "10";
"P07":   PN = "11"  !CDS_PN = "11";
"P10":   PN = "13"  !CDS_PN = "13";
"P11":   PN = "14"  !CDS_PN = "14";
"P12":   PN = "15"  !CDS_PN = "15";
"P13":   PN = "16"  !CDS_PN = "16";
"P14":   PN = "17"  !CDS_PN = "17";
"P15":   PN = "18"  !CDS_PN = "18";
"P16":   PN = "19"  !CDS_PN = "19";
"P17":   PN = "20"  !CDS_PN = "20";
"SCL":   PN = "22"  !CDS_PN = "22";
"SDA":   PN = "23"  !CDS_PN = "23";
"VDD":   PN = "24"  !CDS_PN = "24";
"VSS":   PN = "12"  !CDS_PN = "12";
BODY = "Q_RES","I144": #LOCATION = "R720" !CDS_LOCATION = "R720" &SEC = "1" #&CDS_SEC = "1";
"A":   PN = "1"  !CDS_PN = "1";
"B":   PN = "2"  !CDS_PN = "2";
BODY = "Q_RES","I145": #LOCATION = "R721" !CDS_LOCATION = "R721" &SEC = "1" #&CDS_SEC = "1";
"A":   PN = "1"  !CDS_PN = "1";
"B":   PN = "2"  !CDS_PN = "2";
BODY = "Q_CAP","I146": #LOCATION = "C300" !CDS_LOCATION = "C300" &SEC = "1" #&CDS_SEC = "1";
"A":   PN = "1"  !CDS_PN = "1";
"B":   PN = "2"  !CDS_PN = "2";
BODY = "Q_RES","I147": #LOCATION = "R667" !CDS_LOCATION = "R667" &SEC = "1" #&CDS_SEC = "1";
"A":   PN = "1"  !CDS_PN = "1";
"B":   PN = "2"  !CDS_PN = "2";
BODY = "Q_RES","I152": #LOCATION = "R95" !CDS_LOCATION = "R95" &SEC = "1" #&CDS_SEC = "1";
"A":   PN = "1"  !CDS_PN = "1";
"B":   PN = "2"  !CDS_PN = "2";
BODY = "Q_RES","I153": #LOCATION = "R632" !CDS_LOCATION = "R632" &SEC = "1" #&CDS_SEC = "1";
"A":   PN = "1"  !CDS_PN = "1";
"B":   PN = "2"  !CDS_PN = "2";
BODY = "Q_RES","I161": #LOCATION = "R626" !CDS_LOCATION = "R626" &SEC = "1" #&CDS_SEC = "1";
"A":   PN = "1"  !CDS_PN = "1";
"B":   PN = "2"  !CDS_PN = "2";
BODY = "Q_RES","I162": #LOCATION = "R736" !CDS_LOCATION = "R736" &SEC = "1" #&CDS_SEC = "1";
"A":   PN = "1"  !CDS_PN = "1";
"B":   PN = "2"  !CDS_PN = "2";
BODY = "2N7002A7","I163": #LOCATION = "Q8" !CDS_LOCATION = "Q8" &SEC = "1" #&CDS_SEC = "1";
"D":   PN = "D"  !CDS_PN = "D";
"G":   PN = "G"  !CDS_PN = "G";
"S":   PN = "S"  !CDS_PN = "S";
BODY = "Q_RES","I164": #LOCATION = "R83" !CDS_LOCATION = "R83" &SEC = "1" #&CDS_SEC = "1";
"A":   PN = "1"  !CDS_PN = "1";
"B":   PN = "2"  !CDS_PN = "2";
BODY = "Q_RES","I166": #LOCATION = "R735" !CDS_LOCATION = "R735" &SEC = "1" #&CDS_SEC = "1";
"A":   PN = "1"  !CDS_PN = "1";
"B":   PN = "2"  !CDS_PN = "2";
BODY = "Q_RES","I168": #LOCATION = "R740" !CDS_LOCATION = "R740" #SEC = "1" !CDS_SEC = "1";
"A":   PN = "1"  !CDS_PN = "1";
"B":   PN = "2"  !CDS_PN = "2";
BODY = "Q_RES","I169": #LOCATION = "R739" !CDS_LOCATION = "R739" #SEC = "1" !CDS_SEC = "1";
"A":   PN = "1"  !CDS_PN = "1";
"B":   PN = "2"  !CDS_PN = "2";
BODY = "Q_RES","I171": #LOCATION = "R738" !CDS_LOCATION = "R738" #SEC = "1" !CDS_SEC = "1";
"A":   PN = "1"  !CDS_PN = "1";
"B":   PN = "2"  !CDS_PN = "2";
BODY = "Q_RES","I172": #LOCATION = "R745" !CDS_LOCATION = "R745" &SEC = "1" #&CDS_SEC = "1";
"A":   PN = "1"  !CDS_PN = "1";
"B":   PN = "2"  !CDS_PN = "2";
BODY = "Q_RES","I173": #LOCATION = "R744" !CDS_LOCATION = "R744" &SEC = "1" #&CDS_SEC = "1";
"A":   PN = "1"  !CDS_PN = "1";
"B":   PN = "2"  !CDS_PN = "2";
BODY = "Q_RES","I175": #LOCATION = "R743" !CDS_LOCATION = "R743" &SEC = "1" #&CDS_SEC = "1";
"A":   PN = "1"  !CDS_PN = "1";
"B":   PN = "2"  !CDS_PN = "2";
BODY = "NCP380HSNAJAAT1G","I179": #LOCATION = "U10" !CDS_LOCATION = "U10" #SEC = "1" !CDS_SEC = "1";
"EN":   PN = "3"  !CDS_PN = "3";
"FLAG_N":   PN = "4"  !CDS_PN = "4";
"GND":   PN = "2"  !CDS_PN = "2";
"ILIM":   PN = "5"  !CDS_PN = "5";
"IN":   PN = "1"  !CDS_PN = "1";
"OUT":   PN = "6"  !CDS_PN = "6";
BODY = "74LVC1G07W57","I180": #LOCATION = "U23" !CDS_LOCATION = "U23" &SEC = "1" #&CDS_SEC = "1";
"A":   PN = "2"  !CDS_PN = "2";
"GND":   PN = "3"  !CDS_PN = "3";
"NC1":   PN = "1"  !CDS_PN = "1";
"VCC":   PN = "5"  !CDS_PN = "5";
"Y":   PN = "4"  !CDS_PN = "4";
BODY = "Q_CAP","I181": #LOCATION = "C157" !CDS_LOCATION = "C157" &SEC = "1" #&CDS_SEC = "1";
"A":   PN = "1"  !CDS_PN = "1";
"B":   PN = "2"  !CDS_PN = "2";
BODY = "Q_RES","I183": #LOCATION = "R300" !CDS_LOCATION = "R300" &SEC = "1" #&CDS_SEC = "1";
"A":   PN = "1"  !CDS_PN = "1";
"B":   PN = "2"  !CDS_PN = "2";
BODY = "Q_RES","I184": #LOCATION = "R302" !CDS_LOCATION = "R302" &SEC = "1" #&CDS_SEC = "1";
"A":   PN = "1"  !CDS_PN = "1";
"B":   PN = "2"  !CDS_PN = "2";
BODY = "Q_RES","I185": #LOCATION = "R384" !CDS_LOCATION = "R384" &SEC = "1" #&CDS_SEC = "1";
"A":   PN = "1"  !CDS_PN = "1";
"B":   PN = "2"  !CDS_PN = "2";
DRAWING = "@scm_lib.scm(sch_1):page29";
BODY = "Q_RES","I96": #LOCATION = "R385" !CDS_LOCATION = "R385" &SEC = "1" #&CDS_SEC = "1";
"A":   PN = "1"  !CDS_PN = "1";
"B":   PN = "2"  !CDS_PN = "2";
BODY = "PRTR5V0U2X","I99": #LOCATION = "U38" !CDS_LOCATION = "U38" &SEC = "1" #&CDS_SEC = "1";
"GND":   PN = "1"  !CDS_PN = "1";
"IO1":   PN = "2"  !CDS_PN = "2";
"IO2":   PN = "3"  !CDS_PN = "3";
"VCC":   PN = "4"  !CDS_PN = "4";
BODY = "Q_RES","I101": #LOCATION = "R386" !CDS_LOCATION = "R386" &SEC = "1" #&CDS_SEC = "1";
"A":   PN = "1"  !CDS_PN = "1";
"B":   PN = "2"  !CDS_PN = "2";
BODY = "Q_INDUCTOR4P_12","I102": #LOCATION = "L23" !CDS_LOCATION = "L23" &SEC = "1" #&CDS_SEC = "1";
"1":   PN = "1"  !CDS_PN = "1";
"2":   PN = "2"  !CDS_PN = "2";
"3":   PN = "3"  !CDS_PN = "3";
"4":   PN = "4"  !CDS_PN = "4";
BODY = "Q_RES","I109": #LOCATION = "R675" !CDS_LOCATION = "R675" &SEC = "1" #&CDS_SEC = "1";
"A":   PN = "1"  !CDS_PN = "1";
"B":   PN = "2"  !CDS_PN = "2";
BODY = "Q_RES","I111": #LOCATION = "R668" !CDS_LOCATION = "R668" &SEC = "1" #&CDS_SEC = "1";
"A":   PN = "1"  !CDS_PN = "1";
"B":   PN = "2"  !CDS_PN = "2";
BODY = "Q_INDUCTOR4P_12","I113": #LOCATION = "L22" !CDS_LOCATION = "L22" &SEC = "1" #&CDS_SEC = "1";
"1":   PN = "1"  !CDS_PN = "1";
"2":   PN = "2"  !CDS_PN = "2";
"3":   PN = "3"  !CDS_PN = "3";
"4":   PN = "4"  !CDS_PN = "4";
BODY = "Q_RES","I122": #LOCATION = "R673" !CDS_LOCATION = "R673" &SEC = "1" #&CDS_SEC = "1";
"A":   PN = "1"  !CDS_PN = "1";
"B":   PN = "2"  !CDS_PN = "2";
BODY = "Q_INDUCTOR4P_12","I123": #LOCATION = "L21" !CDS_LOCATION = "L21" &SEC = "1" #&CDS_SEC = "1";
"1":   PN = "1"  !CDS_PN = "1";
"2":   PN = "2"  !CDS_PN = "2";
"3":   PN = "3"  !CDS_PN = "3";
"4":   PN = "4"  !CDS_PN = "4";
BODY = "Q_RES","I124": #LOCATION = "R666" !CDS_LOCATION = "R666" &SEC = "1" #&CDS_SEC = "1";
"A":   PN = "1"  !CDS_PN = "1";
"B":   PN = "2"  !CDS_PN = "2";
BODY = "Q_RES","I135": #LOCATION = "R731" !CDS_LOCATION = "R731" &SEC = "1" #&CDS_SEC = "1";
"A":   PN = "1"  !CDS_PN = "1";
"B":   PN = "2"  !CDS_PN = "2";
BODY = "Q_RES","I136": #LOCATION = "R732" !CDS_LOCATION = "R732" &SEC = "1" #&CDS_SEC = "1";
"A":   PN = "1"  !CDS_PN = "1";
"B":   PN = "2"  !CDS_PN = "2";
BODY = "Q_RES","I141": #LOCATION = "R671" !CDS_LOCATION = "R671" &SEC = "1" #&CDS_SEC = "1";
"A":   PN = "1"  !CDS_PN = "1";
"B":   PN = "2"  !CDS_PN = "2";
BODY = "Q_CAP","I142": #LOCATION = "C238" !CDS_LOCATION = "C238" &SEC = "1" #&CDS_SEC = "1";
"A":   PN = "1"  !CDS_PN = "1";
"B":   PN = "2"  !CDS_PN = "2";
BODY = "Q_CAP","I143": #LOCATION = "C239" !CDS_LOCATION = "C239" &SEC = "1" #&CDS_SEC = "1";
"A":   PN = "1"  !CDS_PN = "1";
"B":   PN = "2"  !CDS_PN = "2";
BODY = "Q_RES","I144": #LOCATION = "R672" !CDS_LOCATION = "R672" &SEC = "1" #&CDS_SEC = "1";
"A":   PN = "1"  !CDS_PN = "1";
"B":   PN = "2"  !CDS_PN = "2";
BODY = "Q_CAP","I146": #LOCATION = "C237" !CDS_LOCATION = "C237" &SEC = "1" #&CDS_SEC = "1";
"A":   PN = "1"  !CDS_PN = "1";
"B":   PN = "2"  !CDS_PN = "2";
BODY = "Q_CAP","I148": #LOCATION = "C236" !CDS_LOCATION = "C236" &SEC = "1" #&CDS_SEC = "1";
"A":   PN = "1"  !CDS_PN = "1";
"B":   PN = "2"  !CDS_PN = "2";
BODY = "Q_CAP","I150": #LOCATION = "C219" !CDS_LOCATION = "C219" &SEC = "1" #&CDS_SEC = "1";
"A":   PN = "1"  !CDS_PN = "1";
"B":   PN = "2"  !CDS_PN = "2";
BODY = "Q_RES","I153": #LOCATION = "R712" !CDS_LOCATION = "R712" &SEC = "1" #&CDS_SEC = "1";
"A":   PN = "1"  !CDS_PN = "1";
"B":   PN = "2"  !CDS_PN = "2";
BODY = "Q_RES","I155": #LOCATION = "R694" !CDS_LOCATION = "R694" &SEC = "1" #&CDS_SEC = "1";
"A":   PN = "1"  !CDS_PN = "1";
"B":   PN = "2"  !CDS_PN = "2";
BODY = "Q_RES","I157": #LOCATION = "R274" !CDS_LOCATION = "R274" &SEC = "1" #&CDS_SEC = "1";
"A":   PN = "1"  !CDS_PN = "1";
"B":   PN = "2"  !CDS_PN = "2";
BODY = "Q_CAP","I161": #LOCATION = "C149" !CDS_LOCATION = "C149" &SEC = "1" #&CDS_SEC = "1";
"A":   PN = "1"  !CDS_PN = "1";
"B":   PN = "2"  !CDS_PN = "2";
BODY = "74HC1G126GW","I164": #LOCATION = "U36" !CDS_LOCATION = "U36" #SEC = "1" !CDS_SEC = "1";
"1":   PN = "1"  !CDS_PN = "1";
"2":   PN = "2"  !CDS_PN = "2";
"4":   PN = "4"  !CDS_PN = "4";
"5":   PN = "5"  !CDS_PN = "5";
"GND":   PN = "3"  !CDS_PN = "3";
BODY = "Q_RES","I166": #LOCATION = "R193" !CDS_LOCATION = "R193" &SEC = "1" #&CDS_SEC = "1";
"A":   PN = "1"  !CDS_PN = "1";
"B":   PN = "2"  !CDS_PN = "2";
BODY = "Q_RES","I170": #LOCATION = "R219" !CDS_LOCATION = "R219" &SEC = "1" #&CDS_SEC = "1";
"A":   PN = "1"  !CDS_PN = "1";
"B":   PN = "2"  !CDS_PN = "2";
BODY = "Q_CAP","I172": #LOCATION = "C148" !CDS_LOCATION = "C148" &SEC = "1" #&CDS_SEC = "1";
"A":   PN = "1"  !CDS_PN = "1";
"B":   PN = "2"  !CDS_PN = "2";
BODY = "74HC1G126GW","I174": #LOCATION = "U29" !CDS_LOCATION = "U29" #SEC = "1" !CDS_SEC = "1";
"1":   PN = "1"  !CDS_PN = "1";
"2":   PN = "2"  !CDS_PN = "2";
"4":   PN = "4"  !CDS_PN = "4";
"5":   PN = "5"  !CDS_PN = "5";
"GND":   PN = "3"  !CDS_PN = "3";
BODY = "Q_RES","I184": #LOCATION = "R205" !CDS_LOCATION = "R205" #SEC = "1" !CDS_SEC = "1";
"A":   PN = "1"  !CDS_PN = "1";
"B":   PN = "2"  !CDS_PN = "2";
BODY = "Q_CAP","I193": #LOCATION = "C179" !CDS_LOCATION = "C179" &SEC = "1" #&CDS_SEC = "1";
"A":   PN = "1"  !CDS_PN = "1";
"B":   PN = "2"  !CDS_PN = "2";
BODY = "Q_CAP","I194": #LOCATION = "C178" !CDS_LOCATION = "C178" &SEC = "1" #&CDS_SEC = "1";
"A":   PN = "1"  !CDS_PN = "1";
"B":   PN = "2"  !CDS_PN = "2";
BODY = "Q_RES","I201": #LOCATION = "R707" !CDS_LOCATION = "R707" &SEC = "1" #&CDS_SEC = "1";
"A":   PN = "1"  !CDS_PN = "1";
"B":   PN = "2"  !CDS_PN = "2";
BODY = "2N7002A7","I202": #LOCATION = "Q6" !CDS_LOCATION = "Q6" &SEC = "1" #&CDS_SEC = "1";
"D":   PN = "D"  !CDS_PN = "D";
"G":   PN = "G"  !CDS_PN = "G";
"S":   PN = "S"  !CDS_PN = "S";
BODY = "Q_RES","I204": #LOCATION = "R730" !CDS_LOCATION = "R730" &SEC = "1" #&CDS_SEC = "1";
"A":   PN = "1"  !CDS_PN = "1";
"B":   PN = "2"  !CDS_PN = "2";
BODY = "PI3PCIE3212ZBEX","I206": LOCATION = "U22" #&CDS_LOCATION = "U22" &SEC = "1" #&CDS_SEC = "1";
"A0_N":   PN = "4"  !CDS_PN = "4";
"A0_P":   PN = "3"  !CDS_PN = "3";
"A1_N":   PN = "8"  !CDS_PN = "8";
"A1_P":   PN = "7"  !CDS_PN = "7";
"B0_N":   PN = "18"  !CDS_PN = "18";
"B0_P":   PN = "19"  !CDS_PN = "19";
"B1_N":   PN = "16"  !CDS_PN = "16";
"B1_P":   PN = "17"  !CDS_PN = "17";
"C0_N":   PN = "14"  !CDS_PN = "14";
"C0_P":   PN = "15"  !CDS_PN = "15";
"C1_N":   PN = "12"  !CDS_PN = "12";
"C1_P":   PN = "13"  !CDS_PN = "13";
"GND0":   PN = "20"  !CDS_PN = "20";
"GND1":   PN = "5"  !CDS_PN = "5";
"GND2":   PN = "11"  !CDS_PN = "11";
"PD":   PN = "2"  !CDS_PN = "2";
"SEL":   PN = "9"  !CDS_PN = "9";
"TH":   PN = "TH"  !CDS_PN = "TH";
"VDD0":   PN = "1"  !CDS_PN = "1";
"VDD1":   PN = "6"  !CDS_PN = "6";
"VDD2":   PN = "10"  !CDS_PN = "10";
BODY = "DT1240E04LP7","I211": #LOCATION = "U27" !CDS_LOCATION = "U27" #SEC = "1" !CDS_SEC = "1";
"IO1":   PN = "1"  !CDS_PN = "1";
"IO2":   PN = "2"  !CDS_PN = "2";
"IO3":   PN = "4"  !CDS_PN = "4";
"IO4":   PN = "5"  !CDS_PN = "5";
"NC1":   PN = "6"  !CDS_PN = "6";
"NC2":   PN = "7"  !CDS_PN = "7";
"NC3":   PN = "9"  !CDS_PN = "9";
"NC4":   PN = "10"  !CDS_PN = "10";
"VSS1":   PN = "3"  !CDS_PN = "3";
"VSS2":   PN = "8"  !CDS_PN = "8";
BODY = "Q_CAP","I219": #LOCATION = "C177" !CDS_LOCATION = "C177" &SEC = "1" #&CDS_SEC = "1";
"A":   PN = "1"  !CDS_PN = "1";
"B":   PN = "2"  !CDS_PN = "2";
BODY = "Q_CAP","I220": #LOCATION = "C327" !CDS_LOCATION = "C327" &SEC = "1" #&CDS_SEC = "1";
"A":   PN = "1"  !CDS_PN = "1";
"B":   PN = "2"  !CDS_PN = "2";
BODY = "CONN9_GSB3111315HR","I221": #LOCATION = "J2" !CDS_LOCATION = "J2" &SEC = "1" #&CDS_SEC = "1";
"D+":   PN = "3"  !CDS_PN = "3";
"D-":   PN = "2"  !CDS_PN = "2";
"G1":   PN = "G1"  !CDS_PN = "G1";
"G2":   PN = "G2"  !CDS_PN = "G2";
"GND":   PN = "4"  !CDS_PN = "4";
"GND_D":   PN = "7"  !CDS_PN = "7";
"SSRX+":   PN = "6"  !CDS_PN = "6";
"SSRX-":   PN = "5"  !CDS_PN = "5";
"SSTX+":   PN = "9"  !CDS_PN = "9";
"SSTX-":   PN = "8"  !CDS_PN = "8";
"VBUS":   PN = "1"  !CDS_PN = "1";
BODY = "Q_RES","I222": #LOCATION = "R693" !CDS_LOCATION = "R693" &SEC = "1" #&CDS_SEC = "1";
"A":   PN = "1"  !CDS_PN = "1";
"B":   PN = "2"  !CDS_PN = "2";
DRAWING = "@scm_lib.scm(sch_1):page30";
BODY = "Q_RES","I146": #LOCATION = "R67" !CDS_LOCATION = "R67" #SEC = "1" !CDS_SEC = "1";
"A":   PN = "1"  !CDS_PN = "1";
"B":   PN = "2"  !CDS_PN = "2";
BODY = "Q_RES","I147": #LOCATION = "R104" !CDS_LOCATION = "R104" #SEC = "1" !CDS_SEC = "1";
"A":   PN = "1"  !CDS_PN = "1";
"B":   PN = "2"  !CDS_PN = "2";
BODY = "Q_RES","I148": #LOCATION = "R102" !CDS_LOCATION = "R102" #SEC = "1" !CDS_SEC = "1";
"A":   PN = "1"  !CDS_PN = "1";
"B":   PN = "2"  !CDS_PN = "2";
BODY = "Q_CAP","I151": #LOCATION = "C175" !CDS_LOCATION = "C175" &SEC = "1" #&CDS_SEC = "1";
"A":   PN = "1"  !CDS_PN = "1";
"B":   PN = "2"  !CDS_PN = "2";
BODY = "SCONN3_21291035BR2","I184": #LOCATION = "J6" !CDS_LOCATION = "J6" #SEC = "1" !CDS_SEC = "1";
"1":   PN = "1"  !CDS_PN = "1";
"2":   PN = "2"  !CDS_PN = "2";
"3":   PN = "3"  !CDS_PN = "3";
BODY = "Q_RES","I192": #LOCATION = "R737" !CDS_LOCATION = "R737" #SEC = "1" !CDS_SEC = "1";
"A":   PN = "1"  !CDS_PN = "1";
"B":   PN = "2"  !CDS_PN = "2";
BODY = "Q_RES","I195": #LOCATION = "R742" !CDS_LOCATION = "R742" #SEC = "1" !CDS_SEC = "1";
"A":   PN = "1"  !CDS_PN = "1";
"B":   PN = "2"  !CDS_PN = "2";
BODY = "Q_RES","I197": #LOCATION = "R741" !CDS_LOCATION = "R741" #SEC = "1" !CDS_SEC = "1";
"A":   PN = "1"  !CDS_PN = "1";
"B":   PN = "2"  !CDS_PN = "2";
BODY = "Q_RES","I221": #LOCATION = "R758" !CDS_LOCATION = "R758" #SEC = "1" !CDS_SEC = "1";
"A":   PN = "1"  !CDS_PN = "1";
"B":   PN = "2"  !CDS_PN = "2";
BODY = "Q_RES","I225": #LOCATION = "R715" !CDS_LOCATION = "R715" #SEC = "1" !CDS_SEC = "1";
"A":   PN = "1"  !CDS_PN = "1";
"B":   PN = "2"  !CDS_PN = "2";
BODY = "Q_RES","I226": #LOCATION = "R757" !CDS_LOCATION = "R757" #SEC = "1" !CDS_SEC = "1";
"A":   PN = "1"  !CDS_PN = "1";
"B":   PN = "2"  !CDS_PN = "2";
BODY = "Q_CAP","I229": #LOCATION = "C268" !CDS_LOCATION = "C268" &SEC = "1" #&CDS_SEC = "1";
"A":   PN = "1"  !CDS_PN = "1";
"B":   PN = "2"  !CDS_PN = "2";
BODY = "Q_RES","I231": #LOCATION = "R72" !CDS_LOCATION = "R72" #SEC = "1" !CDS_SEC = "1";
"A":   PN = "1"  !CDS_PN = "1";
"B":   PN = "2"  !CDS_PN = "2";
BODY = "Q_RES","I237": #LOCATION = "R766" !CDS_LOCATION = "R766" #SEC = "1" !CDS_SEC = "1";
"A":   PN = "1"  !CDS_PN = "1";
"B":   PN = "2"  !CDS_PN = "2";
BODY = "Q_RES","I239": #LOCATION = "R765" !CDS_LOCATION = "R765" #SEC = "1" !CDS_SEC = "1";
"A":   PN = "1"  !CDS_PN = "1";
"B":   PN = "2"  !CDS_PN = "2";
BODY = "74LVC2G07DW7","I246": #LOCATION = "U24" !CDS_LOCATION = "U24" &SEC = "1" #&CDS_SEC = "1";
"1A":   PN = "1"  !CDS_PN = "1";
"1Y":   PN = "6"  !CDS_PN = "6";
"2A":   PN = "3"  !CDS_PN = "3";
"2Y":   PN = "4"  !CDS_PN = "4";
"GND":   PN = "2"  !CDS_PN = "2";
"VCC":   PN = "5"  !CDS_PN = "5";
BODY = "74LVC2G07DW7","I247": #LOCATION = "U47" !CDS_LOCATION = "U47" &SEC = "1" #&CDS_SEC = "1";
"1A":   PN = "1"  !CDS_PN = "1";
"1Y":   PN = "6"  !CDS_PN = "6";
"2A":   PN = "3"  !CDS_PN = "3";
"2Y":   PN = "4"  !CDS_PN = "4";
"GND":   PN = "2"  !CDS_PN = "2";
"VCC":   PN = "5"  !CDS_PN = "5";
BODY = "FSA3357K8X","I250": #LOCATION = "U2" !CDS_LOCATION = "U2" &SEC = "1" #&CDS_SEC = "1";
"A":   PN = "7"  !CDS_PN = "7";
"B0":   PN = "1"  !CDS_PN = "1";
"B1":   PN = "2"  !CDS_PN = "2";
"B2":   PN = "3"  !CDS_PN = "3";
"GND":   PN = "4"  !CDS_PN = "4";
"S1":   PN = "6"  !CDS_PN = "6";
"S2":   PN = "5"  !CDS_PN = "5";
"VCC":   PN = "8"  !CDS_PN = "8";
BODY = "FSA3357K8X","I251": #LOCATION = "U3" !CDS_LOCATION = "U3" &SEC = "1" #&CDS_SEC = "1";
"A":   PN = "7"  !CDS_PN = "7";
"B0":   PN = "1"  !CDS_PN = "1";
"B1":   PN = "2"  !CDS_PN = "2";
"B2":   PN = "3"  !CDS_PN = "3";
"GND":   PN = "4"  !CDS_PN = "4";
"S1":   PN = "6"  !CDS_PN = "6";
"S2":   PN = "5"  !CDS_PN = "5";
"VCC":   PN = "8"  !CDS_PN = "8";
BODY = "Q_CAP","I254": #LOCATION = "C20" !CDS_LOCATION = "C20" #SEC = "1" !CDS_SEC = "1";
"A":   PN = "1"  !CDS_PN = "1";
"B":   PN = "2"  !CDS_PN = "2";
BODY = "Q_CAP","I261": #LOCATION = "C19" !CDS_LOCATION = "C19" #SEC = "1" !CDS_SEC = "1";
"A":   PN = "1"  !CDS_PN = "1";
"B":   PN = "2"  !CDS_PN = "2";
BODY = "Q_RES","I266": #LOCATION = "R726" !CDS_LOCATION = "R726" &SEC = "1" #&CDS_SEC = "1";
"A":   PN = "1"  !CDS_PN = "1";
"B":   PN = "2"  !CDS_PN = "2";
BODY = "Q_RES","I267": #LOCATION = "R39" !CDS_LOCATION = "R39" &SEC = "1" #&CDS_SEC = "1";
"A":   PN = "1"  !CDS_PN = "1";
"B":   PN = "2"  !CDS_PN = "2";
DRAWING = "@scm_lib.scm(sch_1):page31";
BODY = "Q_CAP","I11": #LOCATION = "C501" !CDS_LOCATION = "C501" &SEC = "1" #&CDS_SEC = "1";
"A":   PN = "1"  !CDS_PN = "1";
"B":   PN = "2"  !CDS_PN = "2";
BODY = "Q_CAP","I17": #LOCATION = "C500" !CDS_LOCATION = "C500" &SEC = "1" #&CDS_SEC = "1";
"A":   PN = "1"  !CDS_PN = "1";
"B":   PN = "2"  !CDS_PN = "2";
BODY = "NC7SB3157","I23": #LOCATION = "U50" !CDS_LOCATION = "U50" &SEC = "1" #&CDS_SEC = "1";
"A":   PN = "4"  !CDS_PN = "4";
"B0":   PN = "3"  !CDS_PN = "3";
"B1":   PN = "1"  !CDS_PN = "1";
"GND":   PN = "2"  !CDS_PN = "2";
"S":   PN = "6"  !CDS_PN = "6";
"VCC":   PN = "5"  !CDS_PN = "5";
BODY = "NC7SB3157","I24": #LOCATION = "U51" !CDS_LOCATION = "U51" &SEC = "1" #&CDS_SEC = "1";
"A":   PN = "4"  !CDS_PN = "4";
"B0":   PN = "3"  !CDS_PN = "3";
"B1":   PN = "1"  !CDS_PN = "1";
"GND":   PN = "2"  !CDS_PN = "2";
"S":   PN = "6"  !CDS_PN = "6";
"VCC":   PN = "5"  !CDS_PN = "5";
BODY = "Q_RES","I25": LOCATION = "R538" #&CDS_LOCATION = "R538" &SEC = "1" #&CDS_SEC = "1";
"A":   PN = "1"  !CDS_PN = "1";
"B":   PN = "2"  !CDS_PN = "2";
BODY = "NC7SB3157","I27": LOCATION = "U7" #&CDS_LOCATION = "U7" &SEC = "1" #&CDS_SEC = "1";
"A":   PN = "4"  !CDS_PN = "4";
"B0":   PN = "3"  !CDS_PN = "3";
"B1":   PN = "1"  !CDS_PN = "1";
"GND":   PN = "2"  !CDS_PN = "2";
"S":   PN = "6"  !CDS_PN = "6";
"VCC":   PN = "5"  !CDS_PN = "5";
BODY = "Q_CAP","I31": LOCATION = "C11" #&CDS_LOCATION = "C11" &SEC = "1" #&CDS_SEC = "1";
"A":   PN = "1"  !CDS_PN = "1";
"B":   PN = "2"  !CDS_PN = "2";
BODY = "NC7SB3157","I38": LOCATION = "U20" #&CDS_LOCATION = "U20" &SEC = "1" #&CDS_SEC = "1";
"A":   PN = "4"  !CDS_PN = "4";
"B0":   PN = "3"  !CDS_PN = "3";
"B1":   PN = "1"  !CDS_PN = "1";
"GND":   PN = "2"  !CDS_PN = "2";
"S":   PN = "6"  !CDS_PN = "6";
"VCC":   PN = "5"  !CDS_PN = "5";
BODY = "Q_CAP","I45": LOCATION = "C231" #&CDS_LOCATION = "C231" &SEC = "1" #&CDS_SEC = "1";
"A":   PN = "1"  !CDS_PN = "1";
"B":   PN = "2"  !CDS_PN = "2";
BODY = "SCONN3_212H9103GBR1","I61": #LOCATION = "J13" !CDS_LOCATION = "J13" &SEC = "1" #&CDS_SEC = "1";
"1":   PN = "1"  !CDS_PN = "1";
"2":   PN = "2"  !CDS_PN = "2";
"3":   PN = "3"  !CDS_PN = "3";
BODY = "Q_RES","I70": #LOCATION = "R900" !CDS_LOCATION = "R900" &SEC = "1" #&CDS_SEC = "1";
"A":   PN = "1"  !CDS_PN = "1";
"B":   PN = "2"  !CDS_PN = "2";
BODY = "Q_RES","I71": #LOCATION = "R901" !CDS_LOCATION = "R901" &SEC = "1" #&CDS_SEC = "1";
"A":   PN = "1"  !CDS_PN = "1";
"B":   PN = "2"  !CDS_PN = "2";
BODY = "Q_RES","I72": #LOCATION = "R902" !CDS_LOCATION = "R902" &SEC = "1" #&CDS_SEC = "1";
"A":   PN = "1"  !CDS_PN = "1";
"B":   PN = "2"  !CDS_PN = "2";
BODY = "Q_RES","I73": #LOCATION = "R903" !CDS_LOCATION = "R903" &SEC = "1" #&CDS_SEC = "1";
"A":   PN = "1"  !CDS_PN = "1";
"B":   PN = "2"  !CDS_PN = "2";
BODY = "Q_RES","I74": #LOCATION = "R544" !CDS_LOCATION = "R544" &SEC = "1" #&CDS_SEC = "1";
"A":   PN = "1"  !CDS_PN = "1";
"B":   PN = "2"  !CDS_PN = "2";
BODY = "Q_RES","I75": #LOCATION = "R546" !CDS_LOCATION = "R546" &SEC = "1" #&CDS_SEC = "1";
"A":   PN = "1"  !CDS_PN = "1";
"B":   PN = "2"  !CDS_PN = "2";
BODY = "Q_RES","I76": #LOCATION = "R618" !CDS_LOCATION = "R618" &SEC = "1" #&CDS_SEC = "1";
"A":   PN = "1"  !CDS_PN = "1";
"B":   PN = "2"  !CDS_PN = "2";
BODY = "Q_RES","I77": #LOCATION = "R628" !CDS_LOCATION = "R628" &SEC = "1" #&CDS_SEC = "1";
"A":   PN = "1"  !CDS_PN = "1";
"B":   PN = "2"  !CDS_PN = "2";
BODY = "Q_RES","I78": #LOCATION = "R629" !CDS_LOCATION = "R629" &SEC = "1" #&CDS_SEC = "1";
"A":   PN = "1"  !CDS_PN = "1";
"B":   PN = "2"  !CDS_PN = "2";
BODY = "Q_RES","I79": #LOCATION = "R630" !CDS_LOCATION = "R630" &SEC = "1" #&CDS_SEC = "1";
"A":   PN = "1"  !CDS_PN = "1";
"B":   PN = "2"  !CDS_PN = "2";
BODY = "Q_RES","I80": LOCATION = "R396" #&CDS_LOCATION = "R396" &SEC = "1" #&CDS_SEC = "1";
"A":   PN = "1"  !CDS_PN = "1";
"B":   PN = "2"  !CDS_PN = "2";
DRAWING = "@scm_lib.scm(sch_1):page32";
BODY = "Q_CAP","I21": #LOCATION = "C217" !CDS_LOCATION = "C217" &SEC = "1" #&CDS_SEC = "1";
"A":   PN = "1"  !CDS_PN = "1";
"B":   PN = "2"  !CDS_PN = "2";
BODY = "Q_CAP","I22": #LOCATION = "C215" !CDS_LOCATION = "C215" &SEC = "1" #&CDS_SEC = "1";
"A":   PN = "1"  !CDS_PN = "1";
"B":   PN = "2"  !CDS_PN = "2";
BODY = "Q_RES","I23": #LOCATION = "R518" !CDS_LOCATION = "R518" &SEC = "1" #&CDS_SEC = "1";
"A":   PN = "1"  !CDS_PN = "1";
"B":   PN = "2"  !CDS_PN = "2";
BODY = "Q_RES","I78": #LOCATION = "R223" !CDS_LOCATION = "R223" &SEC = "1" #&CDS_SEC = "1";
"A":   PN = "1"  !CDS_PN = "1";
"B":   PN = "2"  !CDS_PN = "2";
BODY = "Q_RES","I80": #LOCATION = "R222" !CDS_LOCATION = "R222" &SEC = "1" #&CDS_SEC = "1";
"A":   PN = "1"  !CDS_PN = "1";
"B":   PN = "2"  !CDS_PN = "2";
BODY = "Q_RES","I81": #LOCATION = "R221" !CDS_LOCATION = "R221" &SEC = "1" #&CDS_SEC = "1";
"A":   PN = "1"  !CDS_PN = "1";
"B":   PN = "2"  !CDS_PN = "2";
BODY = "Q_RES","I87": #LOCATION = "R224" !CDS_LOCATION = "R224" &SEC = "1" #&CDS_SEC = "1";
"A":   PN = "1"  !CDS_PN = "1";
"B":   PN = "2"  !CDS_PN = "2";
BODY = "Q_RES","I88": #LOCATION = "R639" !CDS_LOCATION = "R639" &SEC = "1" #&CDS_SEC = "1";
"A":   PN = "1"  !CDS_PN = "1";
"B":   PN = "2"  !CDS_PN = "2";
BODY = "Q_RES","I94": #LOCATION = "R514" !CDS_LOCATION = "R514" &SEC = "1" #&CDS_SEC = "1";
"A":   PN = "1"  !CDS_PN = "1";
"B":   PN = "2"  !CDS_PN = "2";
BODY = "Q_RES","I95": #LOCATION = "R516" !CDS_LOCATION = "R516" &SEC = "1" #&CDS_SEC = "1";
"A":   PN = "1"  !CDS_PN = "1";
"B":   PN = "2"  !CDS_PN = "2";
BODY = "Q_RES","I96": #LOCATION = "R515" !CDS_LOCATION = "R515" &SEC = "1" #&CDS_SEC = "1";
"A":   PN = "1"  !CDS_PN = "1";
"B":   PN = "2"  !CDS_PN = "2";
BODY = "Q_RES","I97": #LOCATION = "R517" !CDS_LOCATION = "R517" &SEC = "1" #&CDS_SEC = "1";
"A":   PN = "1"  !CDS_PN = "1";
"B":   PN = "2"  !CDS_PN = "2";
BODY = "Q_RES","I103": #LOCATION = "R226" !CDS_LOCATION = "R226" &SEC = "1" #&CDS_SEC = "1";
"A":   PN = "1"  !CDS_PN = "1";
"B":   PN = "2"  !CDS_PN = "2";
BODY = "Q_RES","I104": #LOCATION = "R227" !CDS_LOCATION = "R227" &SEC = "1" #&CDS_SEC = "1";
"A":   PN = "1"  !CDS_PN = "1";
"B":   PN = "2"  !CDS_PN = "2";
BODY = "Q_RES","I105": #LOCATION = "R230" !CDS_LOCATION = "R230" &SEC = "1" #&CDS_SEC = "1";
"A":   PN = "1"  !CDS_PN = "1";
"B":   PN = "2"  !CDS_PN = "2";
BODY = "Q_RES","I106": #LOCATION = "R229" !CDS_LOCATION = "R229" &SEC = "1" #&CDS_SEC = "1";
"A":   PN = "1"  !CDS_PN = "1";
"B":   PN = "2"  !CDS_PN = "2";
BODY = "Q_RES","I107": #LOCATION = "R228" !CDS_LOCATION = "R228" &SEC = "1" #&CDS_SEC = "1";
"A":   PN = "1"  !CDS_PN = "1";
"B":   PN = "2"  !CDS_PN = "2";
BODY = "Q_RES","I117": #LOCATION = "R203" !CDS_LOCATION = "R203" &SEC = "1" #&CDS_SEC = "1";
"A":   PN = "1"  !CDS_PN = "1";
"B":   PN = "2"  !CDS_PN = "2";
BODY = "Q_RES","I119": #LOCATION = "R523" !CDS_LOCATION = "R523" &SEC = "1" #&CDS_SEC = "1";
"A":   PN = "1"  !CDS_PN = "1";
"B":   PN = "2"  !CDS_PN = "2";
BODY = "Q_RES","I120": #LOCATION = "R204" !CDS_LOCATION = "R204" &SEC = "1" #&CDS_SEC = "1";
"A":   PN = "1"  !CDS_PN = "1";
"B":   PN = "2"  !CDS_PN = "2";
BODY = "Q_RES","I126": #LOCATION = "R510" !CDS_LOCATION = "R510" &SEC = "1" #&CDS_SEC = "1";
"A":   PN = "1"  !CDS_PN = "1";
"B":   PN = "2"  !CDS_PN = "2";
BODY = "Q_RES","I127": #LOCATION = "R511" !CDS_LOCATION = "R511" &SEC = "1" #&CDS_SEC = "1";
"A":   PN = "1"  !CDS_PN = "1";
"B":   PN = "2"  !CDS_PN = "2";
BODY = "Q_RES","I128": #LOCATION = "R513" !CDS_LOCATION = "R513" &SEC = "1" #&CDS_SEC = "1";
"A":   PN = "1"  !CDS_PN = "1";
"B":   PN = "2"  !CDS_PN = "2";
BODY = "Q_RES","I129": #LOCATION = "R512" !CDS_LOCATION = "R512" &SEC = "1" #&CDS_SEC = "1";
"A":   PN = "1"  !CDS_PN = "1";
"B":   PN = "2"  !CDS_PN = "2";
BODY = "Q_RES","I131": #LOCATION = "R834" !CDS_LOCATION = "R834" &SEC = "1" #&CDS_SEC = "1";
"A":   PN = "1"  !CDS_PN = "1";
"B":   PN = "2"  !CDS_PN = "2";
BODY = "CONN8_210HP1080BR1","I132": #LOCATION = "J7" !CDS_LOCATION = "J7" &SEC = "1" #&CDS_SEC = "1";
"1":   PN = "1"  !CDS_PN = "1";
"2":   PN = "2"  !CDS_PN = "2";
"3":   PN = "3"  !CDS_PN = "3";
"4":   PN = "4"  !CDS_PN = "4";
"5":   PN = "5"  !CDS_PN = "5";
"6":   PN = "6"  !CDS_PN = "6";
"7":   PN = "7"  !CDS_PN = "7";
"8":   PN = "8"  !CDS_PN = "8";
BODY = "Q_RES","I140": #LOCATION = "R202" !CDS_LOCATION = "R202" &SEC = "1" #&CDS_SEC = "1";
"A":   PN = "1"  !CDS_PN = "1";
"B":   PN = "2"  !CDS_PN = "2";
BODY = "Q_RES","I141": LOCATION = "R285" #&CDS_LOCATION = "R285" &SEC = "1" #&CDS_SEC = "1";
"A":   PN = "1"  !CDS_PN = "1";
"B":   PN = "2"  !CDS_PN = "2";
BODY = "Q_RES","I143": #LOCATION = "R206" !CDS_LOCATION = "R206" &SEC = "1" #&CDS_SEC = "1";
"A":   PN = "1"  !CDS_PN = "1";
"B":   PN = "2"  !CDS_PN = "2";
BODY = "SCHOTTKY_12","I144": LOCATION = "D20" #&CDS_LOCATION = "D20" &SEC = "1" #&CDS_SEC = "1";
"A":   PN = "1"  !CDS_PN = "1";
"C":   PN = "2"  !CDS_PN = "2";
DRAWING = "@scm_lib.scm(sch_1):page34";
BODY = "LCMXO3LF2100C5BG256C","I1": #LOCATION = "U25" !CDS_LOCATION = "U25" &SEC = "1" #&CDS_SEC = "1";
"PT9A":   PN = "C4"  !CDS_PN = "C4";
"PT9B":   PN = "B5"  !CDS_PN = "B5";
"PT9C":   PN = "B3"  !CDS_PN = "B3";
"PT10A":   PN = "A4"  !CDS_PN = "A4";
"PT10B":   PN = "C5"  !CDS_PN = "C5";
"PT11A":   PN = "A5"  !CDS_PN = "A5";
"PT11B":   PN = "B6"  !CDS_PN = "B6";
"PT11C":   PN = "A3"  !CDS_PN = "A3";
"PT11D":   PN = "B4"  !CDS_PN = "B4";
"PT12A":   PN = "D6"  !CDS_PN = "D6";
"PT12B":   PN = "E7"  !CDS_PN = "E7";
"PT12C||TDO":   PN = "C6"  !CDS_PN = "C6";
"PT12D||TDI":   PN = "A6"  !CDS_PN = "A6";
"PT13A":   PN = "B7"  !CDS_PN = "B7";
"PT13B":   PN = "C7"  !CDS_PN = "C7";
"PT13C":   PN = "E6"  !CDS_PN = "E6";
"PT13D":   PN = "D7"  !CDS_PN = "D7";
"PT16A":   PN = "F7"  !CDS_PN = "F7";
"PT16B":   PN = "E8"  !CDS_PN = "E8";
"PT16C||TCK":   PN = "A7"  !CDS_PN = "A7";
"PT16D||TMS":   PN = "B8"  !CDS_PN = "B8";
"PT17A||PCLKT0_1":   PN = "C8"  !CDS_PN = "C8";
"PT17B||PCLKC0_1":   PN = "A8"  !CDS_PN = "A8";
"PT17C":   PN = "D8"  !CDS_PN = "D8";
"PT17D":   PN = "E9"  !CDS_PN = "E9";
"PT18A":   PN = "F8"  !CDS_PN = "F8";
"PT18B":   PN = "D9"  !CDS_PN = "D9";
"PT18C||SCL||PCLKT0_0":   PN = "A9"  !CDS_PN = "A9";
"PT18D||SDA||PCLKC0_0":   PN = "C9"  !CDS_PN = "C9";
"PT19A":   PN = "B9"  !CDS_PN = "B9";
"PT19B":   PN = "A10"  !CDS_PN = "A10";
"PT19C":   PN = "F9"  !CDS_PN = "F9";
"PT19D":   PN = "E11"  !CDS_PN = "E11";
"PT20A":   PN = "D10"  !CDS_PN = "D10";
"PT20B":   PN = "E10"  !CDS_PN = "E10";
"PT20C||JTAGENB":   PN = "C10"  !CDS_PN = "C10";
"PT20D||PROGRAMN":   PN = "B10"  !CDS_PN = "B10";
"PT21A":   PN = "A11"  !CDS_PN = "A11";
"PT21B":   PN = "C11"  !CDS_PN = "C11";
"PT21C":   PN = "F10"  !CDS_PN = "F10";
"PT21D":   PN = "D11"  !CDS_PN = "D11";
"PT22A":   PN = "B11"  !CDS_PN = "B11";
"PT22B":   PN = "A12"  !CDS_PN = "A12";
"PT22C":   PN = "B13"  !CDS_PN = "B13";
"PT22D":   PN = "A14"  !CDS_PN = "A14";
"PT23A":   PN = "C12"  !CDS_PN = "C12";
"PT23B":   PN = "B12"  !CDS_PN = "B12";
"PT24A":   PN = "B14"  !CDS_PN = "B14";
"PT24B":   PN = "A15"  !CDS_PN = "A15";
"PT24C||INITN":   PN = "A13"  !CDS_PN = "A13";
"PT24D||DONE":   PN = "C13"  !CDS_PN = "C13";
"VCCIO0_D5":   PN = "D5"  !CDS_PN = "D5";
"VCCIO0_D12":   PN = "D12"  !CDS_PN = "D12";
"VCCIO0_G8":   PN = "G8"  !CDS_PN = "G8";
"VCCIO0_G9":   PN = "G9"  !CDS_PN = "G9";
BODY = "Q_RES","I17": #LOCATION = "R625" !CDS_LOCATION = "R625" &SEC = "1" #&CDS_SEC = "1";
"A":   PN = "1"  !CDS_PN = "1";
"B":   PN = "2"  !CDS_PN = "2";
BODY = "Q_RES","I35": #LOCATION = "R571" !CDS_LOCATION = "R571" &SEC = "1" #&CDS_SEC = "1";
"A":   PN = "1"  !CDS_PN = "1";
"B":   PN = "2"  !CDS_PN = "2";
BODY = "Q_RES","I37": #LOCATION = "R634" !CDS_LOCATION = "R634" &SEC = "1" #&CDS_SEC = "1";
"A":   PN = "1"  !CDS_PN = "1";
"B":   PN = "2"  !CDS_PN = "2";
BODY = "Q_RES","I115": #LOCATION = "R809" !CDS_LOCATION = "R809" &SEC = "1" #&CDS_SEC = "1";
"A":   PN = "1"  !CDS_PN = "1";
"B":   PN = "2"  !CDS_PN = "2";
BODY = "Q_RES","I116": #LOCATION = "R810" !CDS_LOCATION = "R810" &SEC = "1" #&CDS_SEC = "1";
"A":   PN = "1"  !CDS_PN = "1";
"B":   PN = "2"  !CDS_PN = "2";
BODY = "Q_RES","I117": #LOCATION = "R808" !CDS_LOCATION = "R808" &SEC = "1" #&CDS_SEC = "1";
"A":   PN = "1"  !CDS_PN = "1";
"B":   PN = "2"  !CDS_PN = "2";
BODY = "Q_RES","I119": #LOCATION = "R806" !CDS_LOCATION = "R806" &SEC = "1" #&CDS_SEC = "1";
"A":   PN = "1"  !CDS_PN = "1";
"B":   PN = "2"  !CDS_PN = "2";
BODY = "Q_CAP","I122": #LOCATION = "C318" !CDS_LOCATION = "C318" &SEC = "1" #&CDS_SEC = "1";
"A":   PN = "1"  !CDS_PN = "1";
"B":   PN = "2"  !CDS_PN = "2";
BODY = "Q_RES","I126": #LOCATION = "R807" !CDS_LOCATION = "R807" &SEC = "1" #&CDS_SEC = "1";
"A":   PN = "1"  !CDS_PN = "1";
"B":   PN = "2"  !CDS_PN = "2";
BODY = "OSC4_7X25000018","I127": #LOCATION = "OSC2" !CDS_LOCATION = "OSC2" &SEC = "1" #&CDS_SEC = "1";
"GND":   PN = "2"  !CDS_PN = "2";
"OE":   PN = "1"  !CDS_PN = "1";
"OUT":   PN = "3"  !CDS_PN = "3";
"VDD":   PN = "4"  !CDS_PN = "4";
BODY = "Q_RES","I137": #LOCATION = "R297" !CDS_LOCATION = "R297" &SEC = "1" #&CDS_SEC = "1";
"A":   PN = "1"  !CDS_PN = "1";
"B":   PN = "2"  !CDS_PN = "2";
BODY = "Q_RES","I139": LOCATION = "R183" #&CDS_LOCATION = "R183" &SEC = "1" #&CDS_SEC = "1";
"A":   PN = "1"  !CDS_PN = "1";
"B":   PN = "2"  !CDS_PN = "2";
BODY = "Q_CAP","I140": LOCATION = "C256" #&CDS_LOCATION = "C256" &SEC = "1" #&CDS_SEC = "1";
"A":   PN = "1"  !CDS_PN = "1";
"B":   PN = "2"  !CDS_PN = "2";
BODY = "Q_CAP","I144": LOCATION = "C257" #&CDS_LOCATION = "C257" &SEC = "1" #&CDS_SEC = "1";
"A":   PN = "1"  !CDS_PN = "1";
"B":   PN = "2"  !CDS_PN = "2";
BODY = "Q_RES","I147": #LOCATION = "R519" !CDS_LOCATION = "R519" &SEC = "1" #&CDS_SEC = "1";
"A":   PN = "1"  !CDS_PN = "1";
"B":   PN = "2"  !CDS_PN = "2";
BODY = "Q_RES","I150": #LOCATION = "R767" !CDS_LOCATION = "R767" &SEC = "1" #&CDS_SEC = "1";
"A":   PN = "1"  !CDS_PN = "1";
"B":   PN = "2"  !CDS_PN = "2";
BODY = "Q_RES","I155": LOCATION = "R10" #&CDS_LOCATION = "R10" #SEC = "1" !CDS_SEC = "1";
"A":   PN = "1"  !CDS_PN = "1";
"B":   PN = "2"  !CDS_PN = "2";
BODY = "Q_RES","I156": #LOCATION = "R123" !CDS_LOCATION = "R123" &SEC = "1" #&CDS_SEC = "1";
"A":   PN = "1"  !CDS_PN = "1";
"B":   PN = "2"  !CDS_PN = "2";
BODY = "Q_RES","I157": #LOCATION = "R718" !CDS_LOCATION = "R718" &SEC = "1" #&CDS_SEC = "1";
"A":   PN = "1"  !CDS_PN = "1";
"B":   PN = "2"  !CDS_PN = "2";
BODY = "Q_RES","I158": #LOCATION = "R837" !CDS_LOCATION = "R837" &SEC = "1" #&CDS_SEC = "1";
"A":   PN = "1"  !CDS_PN = "1";
"B":   PN = "2"  !CDS_PN = "2";
BODY = "Q_RES","I159": #LOCATION = "R459" !CDS_LOCATION = "R459" &SEC = "1" #&CDS_SEC = "1";
"A":   PN = "1"  !CDS_PN = "1";
"B":   PN = "2"  !CDS_PN = "2";
BODY = "Q_RES","I160": #LOCATION = "R434" !CDS_LOCATION = "R434" &SEC = "1" #&CDS_SEC = "1";
"A":   PN = "1"  !CDS_PN = "1";
"B":   PN = "2"  !CDS_PN = "2";
BODY = "Q_RES","I161": #LOCATION = "R435" !CDS_LOCATION = "R435" &SEC = "1" #&CDS_SEC = "1";
"A":   PN = "1"  !CDS_PN = "1";
"B":   PN = "2"  !CDS_PN = "2";
BODY = "Q_RES","I162": #LOCATION = "R436" !CDS_LOCATION = "R436" &SEC = "1" #&CDS_SEC = "1";
"A":   PN = "1"  !CDS_PN = "1";
"B":   PN = "2"  !CDS_PN = "2";
BODY = "Q_RES","I163": #LOCATION = "R437" !CDS_LOCATION = "R437" &SEC = "1" #&CDS_SEC = "1";
"A":   PN = "1"  !CDS_PN = "1";
"B":   PN = "2"  !CDS_PN = "2";
BODY = "Q_RES","I164": #LOCATION = "R270" !CDS_LOCATION = "R270" &SEC = "1" #&CDS_SEC = "1";
"A":   PN = "1"  !CDS_PN = "1";
"B":   PN = "2"  !CDS_PN = "2";
BODY = "Q_RES","I165": #LOCATION = "R272" !CDS_LOCATION = "R272" &SEC = "1" #&CDS_SEC = "1";
"A":   PN = "1"  !CDS_PN = "1";
"B":   PN = "2"  !CDS_PN = "2";
BODY = "Q_RES","I166": #LOCATION = "R303" !CDS_LOCATION = "R303" &SEC = "1" #&CDS_SEC = "1";
"A":   PN = "1"  !CDS_PN = "1";
"B":   PN = "2"  !CDS_PN = "2";
BODY = "Q_RES","I167": #LOCATION = "R397" !CDS_LOCATION = "R397" &SEC = "1" #&CDS_SEC = "1";
"A":   PN = "1"  !CDS_PN = "1";
"B":   PN = "2"  !CDS_PN = "2";
BODY = "Q_RES","I168": #LOCATION = "R447" !CDS_LOCATION = "R447" &SEC = "1" #&CDS_SEC = "1";
"A":   PN = "1"  !CDS_PN = "1";
"B":   PN = "2"  !CDS_PN = "2";
DRAWING = "@scm_lib.scm(sch_1):page35";
BODY = "LCMXO3LF2100C5BG256C","I1": #LOCATION = "U25" !CDS_LOCATION = "U25" &SEC = "2" #&CDS_SEC = "2";
"PR1A":   PN = "D14"  !CDS_PN = "D14";
"PR1B":   PN = "E15"  !CDS_PN = "E15";
"PR1C":   PN = "C15"  !CDS_PN = "C15";
"PR1D":   PN = "B16"  !CDS_PN = "B16";
"PR2A":   PN = "D16"  !CDS_PN = "D16";
"PR2B":   PN = "E14"  !CDS_PN = "E14";
"PR2C":   PN = "C16"  !CDS_PN = "C16";
"PR2D":   PN = "D15"  !CDS_PN = "D15";
"PR3A":   PN = "E16"  !CDS_PN = "E16";
"PR3B":   PN = "F15"  !CDS_PN = "F15";
"PR3C":   PN = "F13"  !CDS_PN = "F13";
"PR3D":   PN = "G12"  !CDS_PN = "G12";
"PR4A":   PN = "F14"  !CDS_PN = "F14";
"PR4B":   PN = "F16"  !CDS_PN = "F16";
"PR4C":   PN = "F12"  !CDS_PN = "F12";
"PR4D":   PN = "G13"  !CDS_PN = "G13";
"PR5A":   PN = "G15"  !CDS_PN = "G15";
"PR5B":   PN = "G14"  !CDS_PN = "G14";
"PR5C":   PN = "G11"  !CDS_PN = "G11";
"PR5D":   PN = "H12"  !CDS_PN = "H12";
"PR6A":   PN = "G16"  !CDS_PN = "G16";
"PR6B":   PN = "H15"  !CDS_PN = "H15";
"PR6C":   PN = "H13"  !CDS_PN = "H13";
"PR6D":   PN = "J12"  !CDS_PN = "J12";
"PR7A||PCLKT1_0":   PN = "H14"  !CDS_PN = "H14";
"PR7B||PCLKC1_0":   PN = "H16"  !CDS_PN = "H16";
"PR7C":   PN = "J16"  !CDS_PN = "J16";
"PR7D":   PN = "J14"  !CDS_PN = "J14";
"PR9A":   PN = "J15"  !CDS_PN = "J15";
"PR9B":   PN = "K16"  !CDS_PN = "K16";
"PR9C":   PN = "H11"  !CDS_PN = "H11";
"PR9D":   PN = "J13"  !CDS_PN = "J13";
"PR10A":   PN = "K14"  !CDS_PN = "K14";
"PR10B":   PN = "K15"  !CDS_PN = "K15";
"PR10C":   PN = "J11"  !CDS_PN = "J11";
"PR10D":   PN = "L12"  !CDS_PN = "L12";
"PR11A":   PN = "L16"  !CDS_PN = "L16";
"PR11B":   PN = "L14"  !CDS_PN = "L14";
"PR11C":   PN = "K13"  !CDS_PN = "K13";
"PR11D":   PN = "K12"  !CDS_PN = "K12";
"PR12A":   PN = "L15"  !CDS_PN = "L15";
"PR12B":   PN = "M16"  !CDS_PN = "M16";
"PR12C":   PN = "K11"  !CDS_PN = "K11";
"PR12D":   PN = "L13"  !CDS_PN = "L13";
"PR13A":   PN = "M14"  !CDS_PN = "M14";
"PR13B":   PN = "M15"  !CDS_PN = "M15";
"PR13C":   PN = "N15"  !CDS_PN = "N15";
"PR13D":   PN = "P16"  !CDS_PN = "P16";
"PR14A":   PN = "N16"  !CDS_PN = "N16";
"PR14B":   PN = "N14"  !CDS_PN = "N14";
"PR14C":   PN = "P15"  !CDS_PN = "P15";
"PR14D":   PN = "R16"  !CDS_PN = "R16";
"VCCIO1_E13":   PN = "E13"  !CDS_PN = "E13";
"VCCIO1_H10":   PN = "H10"  !CDS_PN = "H10";
"VCCIO1_J10":   PN = "J10"  !CDS_PN = "J10";
"VCCIO1_M13":   PN = "M13"  !CDS_PN = "M13";
BODY = "Q_RES","I2": #LOCATION = "R453" !CDS_LOCATION = "R453" &SEC = "1" #&CDS_SEC = "1";
"A":   PN = "1"  !CDS_PN = "1";
"B":   PN = "2"  !CDS_PN = "2";
BODY = "Q_RES","I3": #LOCATION = "R454" !CDS_LOCATION = "R454" &SEC = "1" #&CDS_SEC = "1";
"A":   PN = "1"  !CDS_PN = "1";
"B":   PN = "2"  !CDS_PN = "2";
BODY = "Q_RES","I4": #LOCATION = "R456" !CDS_LOCATION = "R456" &SEC = "1" #&CDS_SEC = "1";
"A":   PN = "1"  !CDS_PN = "1";
"B":   PN = "2"  !CDS_PN = "2";
BODY = "Q_RES","I5": #LOCATION = "R457" !CDS_LOCATION = "R457" &SEC = "1" #&CDS_SEC = "1";
"A":   PN = "1"  !CDS_PN = "1";
"B":   PN = "2"  !CDS_PN = "2";
BODY = "Q_RES","I76": #LOCATION = "R574" !CDS_LOCATION = "R574" #SEC = "1" !CDS_SEC = "1";
"A":   PN = "1"  !CDS_PN = "1";
"B":   PN = "2"  !CDS_PN = "2";
BODY = "Q_RES","I80": #LOCATION = "R51" !CDS_LOCATION = "R51" #SEC = "1" !CDS_SEC = "1";
"A":   PN = "1"  !CDS_PN = "1";
"B":   PN = "2"  !CDS_PN = "2";
BODY = "Q_RES","I88": #LOCATION = "R271" !CDS_LOCATION = "R271" #SEC = "1" !CDS_SEC = "1";
"A":   PN = "1"  !CDS_PN = "1";
"B":   PN = "2"  !CDS_PN = "2";
BODY = "Q_RES","I95": #LOCATION = "R320" !CDS_LOCATION = "R320" #SEC = "1" !CDS_SEC = "1";
"A":   PN = "1"  !CDS_PN = "1";
"B":   PN = "2"  !CDS_PN = "2";
BODY = "Q_RES","I98": #LOCATION = "R318" !CDS_LOCATION = "R318" #SEC = "1" !CDS_SEC = "1";
"A":   PN = "1"  !CDS_PN = "1";
"B":   PN = "2"  !CDS_PN = "2";
BODY = "Q_RES","I99": #LOCATION = "R317" !CDS_LOCATION = "R317" #SEC = "1" !CDS_SEC = "1";
"A":   PN = "1"  !CDS_PN = "1";
"B":   PN = "2"  !CDS_PN = "2";
BODY = "Q_RES","I100": #LOCATION = "R432" !CDS_LOCATION = "R432" #SEC = "1" !CDS_SEC = "1";
"A":   PN = "1"  !CDS_PN = "1";
"B":   PN = "2"  !CDS_PN = "2";
BODY = "Q_RES","I131": LOCATION = "R463" #&CDS_LOCATION = "R463" #SEC = "1" !CDS_SEC = "1";
"A":   PN = "1"  !CDS_PN = "1";
"B":   PN = "2"  !CDS_PN = "2";
BODY = "Q_RES","I136": LOCATION = "R472" #&CDS_LOCATION = "R472" &SEC = "1" #&CDS_SEC = "1";
"A":   PN = "1"  !CDS_PN = "1";
"B":   PN = "2"  !CDS_PN = "2";
BODY = "Q_RES","I137": #LOCATION = "R773" !CDS_LOCATION = "R773" &SEC = "1" #&CDS_SEC = "1";
"A":   PN = "1"  !CDS_PN = "1";
"B":   PN = "2"  !CDS_PN = "2";
BODY = "Q_RES","I138": #LOCATION = "R825" !CDS_LOCATION = "R825" &SEC = "1" #&CDS_SEC = "1";
"A":   PN = "1"  !CDS_PN = "1";
"B":   PN = "2"  !CDS_PN = "2";
BODY = "Q_RES","I139": #LOCATION = "R833" !CDS_LOCATION = "R833" &SEC = "1" #&CDS_SEC = "1";
"A":   PN = "1"  !CDS_PN = "1";
"B":   PN = "2"  !CDS_PN = "2";
BODY = "Q_RES","I140": #LOCATION = "R769" !CDS_LOCATION = "R769" &SEC = "1" #&CDS_SEC = "1";
"A":   PN = "1"  !CDS_PN = "1";
"B":   PN = "2"  !CDS_PN = "2";
BODY = "Q_RES","I141": #LOCATION = "R263" !CDS_LOCATION = "R263" &SEC = "1" #&CDS_SEC = "1";
"A":   PN = "1"  !CDS_PN = "1";
"B":   PN = "2"  !CDS_PN = "2";
BODY = "Q_RES","I142": #LOCATION = "R841" !CDS_LOCATION = "R841" &SEC = "1" #&CDS_SEC = "1";
"A":   PN = "1"  !CDS_PN = "1";
"B":   PN = "2"  !CDS_PN = "2";
BODY = "Q_RES","I143": #LOCATION = "R638" !CDS_LOCATION = "R638" &SEC = "1" #&CDS_SEC = "1";
"A":   PN = "1"  !CDS_PN = "1";
"B":   PN = "2"  !CDS_PN = "2";
BODY = "Q_RES","I144": #LOCATION = "R536" !CDS_LOCATION = "R536" &SEC = "1" #&CDS_SEC = "1";
"A":   PN = "1"  !CDS_PN = "1";
"B":   PN = "2"  !CDS_PN = "2";
BODY = "Q_RES","I145": #LOCATION = "R537" !CDS_LOCATION = "R537" &SEC = "1" #&CDS_SEC = "1";
"A":   PN = "1"  !CDS_PN = "1";
"B":   PN = "2"  !CDS_PN = "2";
BODY = "Q_RES","I146": #LOCATION = "R531" !CDS_LOCATION = "R531" &SEC = "1" #&CDS_SEC = "1";
"A":   PN = "1"  !CDS_PN = "1";
"B":   PN = "2"  !CDS_PN = "2";
BODY = "Q_RES","I147": #LOCATION = "R526" !CDS_LOCATION = "R526" &SEC = "1" #&CDS_SEC = "1";
"A":   PN = "1"  !CDS_PN = "1";
"B":   PN = "2"  !CDS_PN = "2";
BODY = "Q_RES","I148": #LOCATION = "R691" !CDS_LOCATION = "R691" &SEC = "1" #&CDS_SEC = "1";
"A":   PN = "1"  !CDS_PN = "1";
"B":   PN = "2"  !CDS_PN = "2";
BODY = "Q_RES","I149": #LOCATION = "R690" !CDS_LOCATION = "R690" &SEC = "1" #&CDS_SEC = "1";
"A":   PN = "1"  !CDS_PN = "1";
"B":   PN = "2"  !CDS_PN = "2";
BODY = "Q_DIODE","I150": LOCATION = "D23" #&CDS_LOCATION = "D23" &SEC = "1" #&CDS_SEC = "1";
"1":   PN = "1"  !CDS_PN = "1";
"2":   PN = "2"  !CDS_PN = "2";
BODY = "Q_RES","I151": LOCATION = "R886" #&CDS_LOCATION = "R886" &SEC = "1" #&CDS_SEC = "1";
"A":   PN = "1"  !CDS_PN = "1";
"B":   PN = "2"  !CDS_PN = "2";
DRAWING = "@scm_lib.scm(sch_1):page36";
BODY = "LCMXO3LF2100C5BG256C","I1": #LOCATION = "U25" !CDS_LOCATION = "U25" &SEC = "3" #&CDS_SEC = "3";
"PB3A":   PN = "P4"  !CDS_PN = "P4";
"PB3B":   PN = "T4"  !CDS_PN = "T4";
"PB3C":   PN = "T2"  !CDS_PN = "T2";
"PB3D":   PN = "R3"  !CDS_PN = "R3";
"PB5A||CSSPIN":   PN = "R5"  !CDS_PN = "R5";
"PB5B":   PN = "P5"  !CDS_PN = "P5";
"PB6A":   PN = "T5"  !CDS_PN = "T5";
"PB6B":   PN = "R6"  !CDS_PN = "R6";
"PB6C":   PN = "T3"  !CDS_PN = "T3";
"PB6D":   PN = "R4"  !CDS_PN = "R4";
"PB8A||MCLK||CCLK":   PN = "P6"  !CDS_PN = "P6";
"PB8B||SO||SPISO":   PN = "T6"  !CDS_PN = "T6";
"PB8C":   PN = "N6"  !CDS_PN = "N6";
"PB8D":   PN = "L7"  !CDS_PN = "L7";
"PB9A":   PN = "R7"  !CDS_PN = "R7";
"PB9B":   PN = "P7"  !CDS_PN = "P7";
"PB9C":   PN = "M7"  !CDS_PN = "M7";
"PB9D":   PN = "N7"  !CDS_PN = "N7";
"PB11A||PCLKT2_0":   PN = "T7"  !CDS_PN = "T7";
"PB11B||PCLKC2_0":   PN = "R8"  !CDS_PN = "R8";
"PB11C":   PN = "M6"  !CDS_PN = "M6";
"PB11D":   PN = "L8"  !CDS_PN = "L8";
"PB12A":   PN = "P8"  !CDS_PN = "P8";
"PB12B":   PN = "T8"  !CDS_PN = "T8";
"PB12C":   PN = "N8"  !CDS_PN = "N8";
"PB12D":   PN = "L9"  !CDS_PN = "L9";
"PB16A||PCLKT2_1":   PN = "T9"  !CDS_PN = "T9";
"PB16B||PCLKC2_1":   PN = "P9"  !CDS_PN = "P9";
"PB16C":   PN = "M8"  !CDS_PN = "M8";
"PB16D":   PN = "N9"  !CDS_PN = "N9";
"PB18A":   PN = "R9"  !CDS_PN = "R9";
"PB18B":   PN = "T10"  !CDS_PN = "T10";
"PB18C":   PN = "M9"  !CDS_PN = "M9";
"PB18D":   PN = "L10"  !CDS_PN = "L10";
"PB19A":   PN = "P10"  !CDS_PN = "P10";
"PB19B":   PN = "R10"  !CDS_PN = "R10";
"PB19C":   PN = "N10"  !CDS_PN = "N10";
"PB19D":   PN = "M11"  !CDS_PN = "M11";
"PB21A":   PN = "T11"  !CDS_PN = "T11";
"PB21B":   PN = "P11"  !CDS_PN = "P11";
"PB21C":   PN = "M10"  !CDS_PN = "M10";
"PB21D":   PN = "N11"  !CDS_PN = "N11";
"PB22A":   PN = "R11"  !CDS_PN = "R11";
"PB22B":   PN = "T12"  !CDS_PN = "T12";
"PB22C":   PN = "R13"  !CDS_PN = "R13";
"PB22D":   PN = "T14"  !CDS_PN = "T14";
"PB24A":   PN = "P12"  !CDS_PN = "P12";
"PB24B":   PN = "T13"  !CDS_PN = "T13";
"PB25A||SN":   PN = "R12"  !CDS_PN = "R12";
"PB25B||SI||SISPI":   PN = "P13"  !CDS_PN = "P13";
"PB25C":   PN = "T15"  !CDS_PN = "T15";
"PB25D":   PN = "R14"  !CDS_PN = "R14";
"VCCIO2_K8":   PN = "K8"  !CDS_PN = "K8";
"VCCIO2_K9":   PN = "K9"  !CDS_PN = "K9";
"VCCIO2_N5":   PN = "N5"  !CDS_PN = "N5";
"VCCIO2_N12":   PN = "N12"  !CDS_PN = "N12";
BODY = "Q_RES","I2": #LOCATION = "R575" !CDS_LOCATION = "R575" #SEC = "1" !CDS_SEC = "1";
"A":   PN = "1"  !CDS_PN = "1";
"B":   PN = "2"  !CDS_PN = "2";
BODY = "Q_RES","I3": #LOCATION = "R577" !CDS_LOCATION = "R577" #SEC = "1" !CDS_SEC = "1";
"A":   PN = "1"  !CDS_PN = "1";
"B":   PN = "2"  !CDS_PN = "2";
BODY = "Q_RES","I7": #LOCATION = "R579" !CDS_LOCATION = "R579" #SEC = "1" !CDS_SEC = "1";
"A":   PN = "1"  !CDS_PN = "1";
"B":   PN = "2"  !CDS_PN = "2";
BODY = "Q_RES","I8": #LOCATION = "R578" !CDS_LOCATION = "R578" #SEC = "1" !CDS_SEC = "1";
"A":   PN = "1"  !CDS_PN = "1";
"B":   PN = "2"  !CDS_PN = "2";
BODY = "Q_RES","I9": #LOCATION = "R747" !CDS_LOCATION = "R747" #SEC = "1" !CDS_SEC = "1";
"A":   PN = "1"  !CDS_PN = "1";
"B":   PN = "2"  !CDS_PN = "2";
BODY = "Q_RES","I10": #LOCATION = "R746" !CDS_LOCATION = "R746" #SEC = "1" !CDS_SEC = "1";
"A":   PN = "1"  !CDS_PN = "1";
"B":   PN = "2"  !CDS_PN = "2";
BODY = "Q_RES","I33": #LOCATION = "R321" !CDS_LOCATION = "R321" #SEC = "1" !CDS_SEC = "1";
"A":   PN = "1"  !CDS_PN = "1";
"B":   PN = "2"  !CDS_PN = "2";
BODY = "Q_RES","I34": #LOCATION = "R323" !CDS_LOCATION = "R323" #SEC = "1" !CDS_SEC = "1";
"A":   PN = "1"  !CDS_PN = "1";
"B":   PN = "2"  !CDS_PN = "2";
BODY = "Q_RES","I35": #LOCATION = "R322" !CDS_LOCATION = "R322" #SEC = "1" !CDS_SEC = "1";
"A":   PN = "1"  !CDS_PN = "1";
"B":   PN = "2"  !CDS_PN = "2";
BODY = "Q_RES","I36": #LOCATION = "R379" !CDS_LOCATION = "R379" #SEC = "1" !CDS_SEC = "1";
"A":   PN = "1"  !CDS_PN = "1";
"B":   PN = "2"  !CDS_PN = "2";
BODY = "Q_RES","I42": #LOCATION = "R898" !CDS_LOCATION = "R898" #SEC = "1" !CDS_SEC = "1";
"A":   PN = "1"  !CDS_PN = "1";
"B":   PN = "2"  !CDS_PN = "2";
BODY = "Q_RES","I43": #LOCATION = "R899" !CDS_LOCATION = "R899" #SEC = "1" !CDS_SEC = "1";
"A":   PN = "1"  !CDS_PN = "1";
"B":   PN = "2"  !CDS_PN = "2";
BODY = "Q_RES","I46": LOCATION = "R220" #&CDS_LOCATION = "R220" &SEC = "1" #&CDS_SEC = "1";
"A":   PN = "1"  !CDS_PN = "1";
"B":   PN = "2"  !CDS_PN = "2";
BODY = "Q_RES","I47": LOCATION = "R134" #&CDS_LOCATION = "R134" &SEC = "1" #&CDS_SEC = "1";
"A":   PN = "1"  !CDS_PN = "1";
"B":   PN = "2"  !CDS_PN = "2";
BODY = "Q_RES","I50": LOCATION = "R288" #&CDS_LOCATION = "R288" &SEC = "1" #&CDS_SEC = "1";
"A":   PN = "1"  !CDS_PN = "1";
"B":   PN = "2"  !CDS_PN = "2";
BODY = "Q_RES","I57": LOCATION = "R114" #&CDS_LOCATION = "R114" #SEC = "1" !CDS_SEC = "1";
"A":   PN = "1"  !CDS_PN = "1";
"B":   PN = "2"  !CDS_PN = "2";
BODY = "Q_RES","I58": LOCATION = "R105" #&CDS_LOCATION = "R105" #SEC = "1" !CDS_SEC = "1";
"A":   PN = "1"  !CDS_PN = "1";
"B":   PN = "2"  !CDS_PN = "2";
BODY = "Q_RES","I78": #LOCATION = "R748" !CDS_LOCATION = "R748" &SEC = "1" #&CDS_SEC = "1";
"A":   PN = "1"  !CDS_PN = "1";
"B":   PN = "2"  !CDS_PN = "2";
BODY = "Q_RES","I80": #LOCATION = "R635" !CDS_LOCATION = "R635" &SEC = "1" #&CDS_SEC = "1";
"A":   PN = "1"  !CDS_PN = "1";
"B":   PN = "2"  !CDS_PN = "2";
BODY = "Q_RES","I81": #LOCATION = "R445" !CDS_LOCATION = "R445" &SEC = "1" #&CDS_SEC = "1";
"A":   PN = "1"  !CDS_PN = "1";
"B":   PN = "2"  !CDS_PN = "2";
BODY = "Q_RES","I82": #LOCATION = "R750" !CDS_LOCATION = "R750" &SEC = "1" #&CDS_SEC = "1";
"A":   PN = "1"  !CDS_PN = "1";
"B":   PN = "2"  !CDS_PN = "2";
DRAWING = "@scm_lib.scm(sch_1):page37";
BODY = "LCMXO3LF2100C5BG256C","I1": #LOCATION = "U25" !CDS_LOCATION = "U25" &SEC = "4" #&CDS_SEC = "4";
"PL11A":   PN = "L1"  !CDS_PN = "L1";
"PL11B":   PN = "L3"  !CDS_PN = "L3";
"PL11C":   PN = "K4"  !CDS_PN = "K4";
"PL11D":   PN = "L5"  !CDS_PN = "L5";
"PL12A||PCLKT3_0":   PN = "L2"  !CDS_PN = "L2";
"PL12B||PCLKC3_0":   PN = "M1"  !CDS_PN = "M1";
"PL12C":   PN = "K5"  !CDS_PN = "K5";
"PL12D":   PN = "L4"  !CDS_PN = "L4";
"PL13A":   PN = "M3"  !CDS_PN = "M3";
"PL13B":   PN = "N1"  !CDS_PN = "N1";
"PL13C":   PN = "N2"  !CDS_PN = "N2";
"PL13D":   PN = "P1"  !CDS_PN = "P1";
"PL14A":   PN = "M2"  !CDS_PN = "M2";
"PL14B":   PN = "N3"  !CDS_PN = "N3";
"PL14C":   PN = "R1"  !CDS_PN = "R1";
"PL14D":   PN = "P2"  !CDS_PN = "P2";
"VCCIO3":   PN = "M4"  !CDS_PN = "M4";
DRAWING = "@scm_lib.scm(sch_1):page38";
BODY = "LCMXO3LF2100C5BG256C","I1": #LOCATION = "U25" !CDS_LOCATION = "U25" &SEC = "5" #&CDS_SEC = "5";
"PL6A":   PN = "G1"  !CDS_PN = "G1";
"PL6B":   PN = "H2"  !CDS_PN = "H2";
"PL6C":   PN = "H4"  !CDS_PN = "H4";
"PL6D":   PN = "J6"  !CDS_PN = "J6";
"PL7A":   PN = "H3"  !CDS_PN = "H3";
"PL7B":   PN = "H1"  !CDS_PN = "H1";
"PL7C||PCLKT4_0":   PN = "J1"  !CDS_PN = "J1";
"PL7D||PCLKC4_0":   PN = "J3"  !CDS_PN = "J3";
"PL9A":   PN = "J2"  !CDS_PN = "J2";
"PL9B":   PN = "K1"  !CDS_PN = "K1";
"PL9C":   PN = "H5"  !CDS_PN = "H5";
"PL9D":   PN = "J4"  !CDS_PN = "J4";
"PL10A":   PN = "K3"  !CDS_PN = "K3";
"PL10B":   PN = "K2"  !CDS_PN = "K2";
"PL10C":   PN = "J5"  !CDS_PN = "J5";
"PL10D":   PN = "K6"  !CDS_PN = "K6";
"VCCIO4_H7":   PN = "H7"  !CDS_PN = "H7";
"VCCIO4_J7":   PN = "J7"  !CDS_PN = "J7";
DRAWING = "@scm_lib.scm(sch_1):page39";
BODY = "LCMXO3LF2100C5BG256C","I1": #LOCATION = "U25" !CDS_LOCATION = "U25" &SEC = "6" #&CDS_SEC = "6";
"PL1A||L_GPLLT_FB":   PN = "D3"  !CDS_PN = "D3";
"PL1B||L_GPLLC_FB":   PN = "D1"  !CDS_PN = "D1";
"PL1C":   PN = "B1"  !CDS_PN = "B1";
"PL1D":   PN = "C2"  !CDS_PN = "C2";
"PL2A||L_GPLLT_IN":   PN = "E2"  !CDS_PN = "E2";
"PL2B||L_GPLLC_IN":   PN = "E3"  !CDS_PN = "E3";
"PL2C":   PN = "C1"  !CDS_PN = "C1";
"PL2D":   PN = "D2"  !CDS_PN = "D2";
"PL3A||PCLKT5_0":   PN = "E1"  !CDS_PN = "E1";
"PL3B||PCLKC5_0":   PN = "F2"  !CDS_PN = "F2";
"PL3C":   PN = "F4"  !CDS_PN = "F4";
"PL3D":   PN = "G6"  !CDS_PN = "G6";
"PL4A":   PN = "F3"  !CDS_PN = "F3";
"PL4B":   PN = "F1"  !CDS_PN = "F1";
"PL4C":   PN = "G5"  !CDS_PN = "G5";
"PL4D":   PN = "G4"  !CDS_PN = "G4";
"PL5A":   PN = "G2"  !CDS_PN = "G2";
"PL5B":   PN = "G3"  !CDS_PN = "G3";
"PL5C":   PN = "F5"  !CDS_PN = "F5";
"PL5D":   PN = "H6"  !CDS_PN = "H6";
"VCCIO5":   PN = "E4"  !CDS_PN = "E4";
DRAWING = "@scm_lib.scm(sch_1):page40";
BODY = "LCMXO3LF2100C5BG256C","I1": #LOCATION = "U25" !CDS_LOCATION = "U25" &SEC = "7" #&CDS_SEC = "7";
"GND_B2":   PN = "B2"  !CDS_PN = "B2";
"GND_B15":   PN = "B15"  !CDS_PN = "B15";
"GND_C3":   PN = "C3"  !CDS_PN = "C3";
"GND_C14":   PN = "C14"  !CDS_PN = "C14";
"GND_D4":   PN = "D4"  !CDS_PN = "D4";
"GND_D13":   PN = "D13"  !CDS_PN = "D13";
"GND_E5":   PN = "E5"  !CDS_PN = "E5";
"GND_E12":   PN = "E12"  !CDS_PN = "E12";
"GND_F6":   PN = "F6"  !CDS_PN = "F6";
"GND_F11":   PN = "F11"  !CDS_PN = "F11";
"GND_H8":   PN = "H8"  !CDS_PN = "H8";
"GND_H9":   PN = "H9"  !CDS_PN = "H9";
"GND_J8":   PN = "J8"  !CDS_PN = "J8";
"GND_J9":   PN = "J9"  !CDS_PN = "J9";
"GND_L6":   PN = "L6"  !CDS_PN = "L6";
"GND_L11":   PN = "L11"  !CDS_PN = "L11";
"GND_M5":   PN = "M5"  !CDS_PN = "M5";
"GND_M12":   PN = "M12"  !CDS_PN = "M12";
"GND_N4":   PN = "N4"  !CDS_PN = "N4";
"GND_N13":   PN = "N13"  !CDS_PN = "N13";
"GND_P3":   PN = "P3"  !CDS_PN = "P3";
"GND_P14":   PN = "P14"  !CDS_PN = "P14";
"GND_R2":   PN = "R2"  !CDS_PN = "R2";
"GND_R15":   PN = "R15"  !CDS_PN = "R15";
"NC1":   PN = "A2"  !CDS_PN = "A2";
"VCC_A1":   PN = "A1"  !CDS_PN = "A1";
"VCC_A16":   PN = "A16"  !CDS_PN = "A16";
"VCC_G7":   PN = "G7"  !CDS_PN = "G7";
"VCC_G10":   PN = "G10"  !CDS_PN = "G10";
"VCC_K7":   PN = "K7"  !CDS_PN = "K7";
"VCC_K10":   PN = "K10"  !CDS_PN = "K10";
"VCC_T1":   PN = "T1"  !CDS_PN = "T1";
"VCC_T16":   PN = "T16"  !CDS_PN = "T16";
DRAWING = "@scm_lib.scm(sch_1):page41";
BODY = "Q_CAP","I1": LOCATION = "C242" #&CDS_LOCATION = "C242" &SEC = "1" #&CDS_SEC = "1";
"A":   PN = "1"  !CDS_PN = "1";
"B":   PN = "2"  !CDS_PN = "2";
BODY = "Q_CAP","I8": LOCATION = "C166" #&CDS_LOCATION = "C166" &SEC = "1" #&CDS_SEC = "1";
"A":   PN = "1"  !CDS_PN = "1";
"B":   PN = "2"  !CDS_PN = "2";
BODY = "Q_RES","I71": LOCATION = "R305" #&CDS_LOCATION = "R305" &SEC = "1" #&CDS_SEC = "1";
"A":   PN = "1"  !CDS_PN = "1";
"B":   PN = "2"  !CDS_PN = "2";
BODY = "Q_RES","I72": LOCATION = "R525" #&CDS_LOCATION = "R525" &SEC = "1" #&CDS_SEC = "1";
"A":   PN = "1"  !CDS_PN = "1";
"B":   PN = "2"  !CDS_PN = "2";
BODY = "Q_RES","I73": LOCATION = "R304" #&CDS_LOCATION = "R304" &SEC = "1" #&CDS_SEC = "1";
"A":   PN = "1"  !CDS_PN = "1";
"B":   PN = "2"  !CDS_PN = "2";
BODY = "Q_RES","I74": LOCATION = "R308" #&CDS_LOCATION = "R308" &SEC = "1" #&CDS_SEC = "1";
"A":   PN = "1"  !CDS_PN = "1";
"B":   PN = "2"  !CDS_PN = "2";
BODY = "Q_RES","I75": LOCATION = "R301" #&CDS_LOCATION = "R301" &SEC = "1" #&CDS_SEC = "1";
"A":   PN = "1"  !CDS_PN = "1";
"B":   PN = "2"  !CDS_PN = "2";
BODY = "Q_RES","I76": LOCATION = "R307" #&CDS_LOCATION = "R307" &SEC = "1" #&CDS_SEC = "1";
"A":   PN = "1"  !CDS_PN = "1";
"B":   PN = "2"  !CDS_PN = "2";
BODY = "Q_CAP","I77": LOCATION = "C247" #&CDS_LOCATION = "C247" &SEC = "1" #&CDS_SEC = "1";
"A":   PN = "1"  !CDS_PN = "1";
"B":   PN = "2"  !CDS_PN = "2";
BODY = "Q_CAP","I78": LOCATION = "C189" #&CDS_LOCATION = "C189" &SEC = "1" #&CDS_SEC = "1";
"A":   PN = "1"  !CDS_PN = "1";
"B":   PN = "2"  !CDS_PN = "2";
BODY = "Q_CAP","I79": LOCATION = "C261" #&CDS_LOCATION = "C261" &SEC = "1" #&CDS_SEC = "1";
"A":   PN = "1"  !CDS_PN = "1";
"B":   PN = "2"  !CDS_PN = "2";
BODY = "Q_CAP","I80": LOCATION = "C167" #&CDS_LOCATION = "C167" &SEC = "1" #&CDS_SEC = "1";
"A":   PN = "1"  !CDS_PN = "1";
"B":   PN = "2"  !CDS_PN = "2";
BODY = "Q_CAP","I81": LOCATION = "C243" #&CDS_LOCATION = "C243" &SEC = "1" #&CDS_SEC = "1";
"A":   PN = "1"  !CDS_PN = "1";
"B":   PN = "2"  !CDS_PN = "2";
BODY = "Q_CAP","I82": LOCATION = "C254" #&CDS_LOCATION = "C254" &SEC = "1" #&CDS_SEC = "1";
"A":   PN = "1"  !CDS_PN = "1";
"B":   PN = "2"  !CDS_PN = "2";
BODY = "Q_CAP","I83": LOCATION = "C141" #&CDS_LOCATION = "C141" &SEC = "1" #&CDS_SEC = "1";
"A":   PN = "1"  !CDS_PN = "1";
"B":   PN = "2"  !CDS_PN = "2";
BODY = "Q_CAP","I84": LOCATION = "C187" #&CDS_LOCATION = "C187" &SEC = "1" #&CDS_SEC = "1";
"A":   PN = "1"  !CDS_PN = "1";
"B":   PN = "2"  !CDS_PN = "2";
BODY = "Q_CAP","I85": LOCATION = "C245" #&CDS_LOCATION = "C245" &SEC = "1" #&CDS_SEC = "1";
"A":   PN = "1"  !CDS_PN = "1";
"B":   PN = "2"  !CDS_PN = "2";
BODY = "Q_CAP","I86": LOCATION = "C188" #&CDS_LOCATION = "C188" &SEC = "1" #&CDS_SEC = "1";
"A":   PN = "1"  !CDS_PN = "1";
"B":   PN = "2"  !CDS_PN = "2";
BODY = "Q_CAP","I87": LOCATION = "C260" #&CDS_LOCATION = "C260" &SEC = "1" #&CDS_SEC = "1";
"A":   PN = "1"  !CDS_PN = "1";
"B":   PN = "2"  !CDS_PN = "2";
BODY = "Q_CAP","I88": LOCATION = "C152" #&CDS_LOCATION = "C152" &SEC = "1" #&CDS_SEC = "1";
"A":   PN = "1"  !CDS_PN = "1";
"B":   PN = "2"  !CDS_PN = "2";
BODY = "Q_CAP","I89": LOCATION = "C160" #&CDS_LOCATION = "C160" &SEC = "1" #&CDS_SEC = "1";
"A":   PN = "1"  !CDS_PN = "1";
"B":   PN = "2"  !CDS_PN = "2";
BODY = "Q_CAP","I90": LOCATION = "C220" #&CDS_LOCATION = "C220" &SEC = "1" #&CDS_SEC = "1";
"A":   PN = "1"  !CDS_PN = "1";
"B":   PN = "2"  !CDS_PN = "2";
BODY = "Q_CAP","I91": LOCATION = "C162" #&CDS_LOCATION = "C162" &SEC = "1" #&CDS_SEC = "1";
"A":   PN = "1"  !CDS_PN = "1";
"B":   PN = "2"  !CDS_PN = "2";
BODY = "Q_CAP","I92": LOCATION = "C164" #&CDS_LOCATION = "C164" &SEC = "1" #&CDS_SEC = "1";
"A":   PN = "1"  !CDS_PN = "1";
"B":   PN = "2"  !CDS_PN = "2";
BODY = "Q_CAP","I93": LOCATION = "C165" #&CDS_LOCATION = "C165" &SEC = "1" #&CDS_SEC = "1";
"A":   PN = "1"  !CDS_PN = "1";
"B":   PN = "2"  !CDS_PN = "2";
BODY = "Q_CAP","I94": LOCATION = "C216" #&CDS_LOCATION = "C216" &SEC = "1" #&CDS_SEC = "1";
"A":   PN = "1"  !CDS_PN = "1";
"B":   PN = "2"  !CDS_PN = "2";
BODY = "Q_CAP","I95": LOCATION = "C218" #&CDS_LOCATION = "C218" &SEC = "1" #&CDS_SEC = "1";
"A":   PN = "1"  !CDS_PN = "1";
"B":   PN = "2"  !CDS_PN = "2";
BODY = "Q_CAP","I96": LOCATION = "C195" #&CDS_LOCATION = "C195" &SEC = "1" #&CDS_SEC = "1";
"A":   PN = "1"  !CDS_PN = "1";
"B":   PN = "2"  !CDS_PN = "2";
BODY = "Q_CAP","I99": LOCATION = "C145" #&CDS_LOCATION = "C145" #SEC = "1" !CDS_SEC = "1";
"A":   PN = "1"  !CDS_PN = "1";
"B":   PN = "2"  !CDS_PN = "2";
BODY = "Q_CAP","I101": LOCATION = "C194" #&CDS_LOCATION = "C194" &SEC = "1" #&CDS_SEC = "1";
"A":   PN = "1"  !CDS_PN = "1";
"B":   PN = "2"  !CDS_PN = "2";
BODY = "Q_INDUCTOR","I107": LOCATION = "L19" #&CDS_LOCATION = "L19" &SEC = "1" #&CDS_SEC = "1";
"1":   PN = "1"  !CDS_PN = "1";
"2":   PN = "2"  !CDS_PN = "2";
BODY = "Q_CAP","I108": LOCATION = "C176" #&CDS_LOCATION = "C176" #SEC = "1" !CDS_SEC = "1";
"A":   PN = "1"  !CDS_PN = "1";
"B":   PN = "2"  !CDS_PN = "2";
BODY = "Q_CAP","I109": LOCATION = "C193" #&CDS_LOCATION = "C193" #SEC = "1" !CDS_SEC = "1";
"A":   PN = "1"  !CDS_PN = "1";
"B":   PN = "2"  !CDS_PN = "2";
BODY = "Q_CAP","I115": LOCATION = "C250" #&CDS_LOCATION = "C250" &SEC = "1" #&CDS_SEC = "1";
"A":   PN = "1"  !CDS_PN = "1";
"B":   PN = "2"  !CDS_PN = "2";
BODY = "Q_CAP","I116": LOCATION = "C190" #&CDS_LOCATION = "C190" &SEC = "1" #&CDS_SEC = "1";
"A":   PN = "1"  !CDS_PN = "1";
"B":   PN = "2"  !CDS_PN = "2";
BODY = "Q_CAP","I117": LOCATION = "C263" #&CDS_LOCATION = "C263" &SEC = "1" #&CDS_SEC = "1";
"A":   PN = "1"  !CDS_PN = "1";
"B":   PN = "2"  !CDS_PN = "2";
BODY = "Q_CAP","I118": LOCATION = "C269" #&CDS_LOCATION = "C269" &SEC = "1" #&CDS_SEC = "1";
"A":   PN = "1"  !CDS_PN = "1";
"B":   PN = "2"  !CDS_PN = "2";
BODY = "Q_CAP","I119": LOCATION = "C266" #&CDS_LOCATION = "C266" &SEC = "1" #&CDS_SEC = "1";
"A":   PN = "1"  !CDS_PN = "1";
"B":   PN = "2"  !CDS_PN = "2";
BODY = "Q_CAP","I122": LOCATION = "C163" #&CDS_LOCATION = "C163" &SEC = "1" #&CDS_SEC = "1";
"A":   PN = "1"  !CDS_PN = "1";
"B":   PN = "2"  !CDS_PN = "2";
BODY = "Q_CAP","I123": LOCATION = "C286" #&CDS_LOCATION = "C286" &SEC = "1" #&CDS_SEC = "1";
"A":   PN = "1"  !CDS_PN = "1";
"B":   PN = "2"  !CDS_PN = "2";
BODY = "Q_CAP","I124": LOCATION = "C285" #&CDS_LOCATION = "C285" &SEC = "1" #&CDS_SEC = "1";
"A":   PN = "1"  !CDS_PN = "1";
"B":   PN = "2"  !CDS_PN = "2";
BODY = "Q_CAP","I125": LOCATION = "C281" #&CDS_LOCATION = "C281" &SEC = "1" #&CDS_SEC = "1";
"A":   PN = "1"  !CDS_PN = "1";
"B":   PN = "2"  !CDS_PN = "2";
BODY = "Q_CAP","I126": LOCATION = "C283" #&CDS_LOCATION = "C283" &SEC = "1" #&CDS_SEC = "1";
"A":   PN = "1"  !CDS_PN = "1";
"B":   PN = "2"  !CDS_PN = "2";
DRAWING = "@scm_lib.scm(sch_1):page42";
BODY = "Q_RES","I7": #LOCATION = "R627" !CDS_LOCATION = "R627" &SEC = "1" #&CDS_SEC = "1";
"A":   PN = "1"  !CDS_PN = "1";
"B":   PN = "2"  !CDS_PN = "2";
BODY = "Q_RES","I13": #LOCATION = "R621" !CDS_LOCATION = "R621" &SEC = "1" #&CDS_SEC = "1";
"A":   PN = "1"  !CDS_PN = "1";
"B":   PN = "2"  !CDS_PN = "2";
BODY = "Q_RES","I27": #LOCATION = "R608" !CDS_LOCATION = "R608" &SEC = "1" #&CDS_SEC = "1";
"A":   PN = "1"  !CDS_PN = "1";
"B":   PN = "2"  !CDS_PN = "2";
BODY = "Q_RES","I29": #LOCATION = "R607" !CDS_LOCATION = "R607" &SEC = "1" #&CDS_SEC = "1";
"A":   PN = "1"  !CDS_PN = "1";
"B":   PN = "2"  !CDS_PN = "2";
BODY = "Q_RES","I37": #LOCATION = "R595" !CDS_LOCATION = "R595" &SEC = "1" #&CDS_SEC = "1";
"A":   PN = "1"  !CDS_PN = "1";
"B":   PN = "2"  !CDS_PN = "2";
BODY = "Q_RES","I39": #LOCATION = "R593" !CDS_LOCATION = "R593" &SEC = "1" #&CDS_SEC = "1";
"A":   PN = "1"  !CDS_PN = "1";
"B":   PN = "2"  !CDS_PN = "2";
BODY = "Q_RES","I53": #LOCATION = "R641" !CDS_LOCATION = "R641" &SEC = "1" #&CDS_SEC = "1";
"A":   PN = "1"  !CDS_PN = "1";
"B":   PN = "2"  !CDS_PN = "2";
BODY = "Q_RES","I56": #LOCATION = "R640" !CDS_LOCATION = "R640" &SEC = "1" #&CDS_SEC = "1";
"A":   PN = "1"  !CDS_PN = "1";
"B":   PN = "2"  !CDS_PN = "2";
BODY = "Q_RES","I58": #LOCATION = "R642" !CDS_LOCATION = "R642" &SEC = "1" #&CDS_SEC = "1";
"A":   PN = "1"  !CDS_PN = "1";
"B":   PN = "2"  !CDS_PN = "2";
BODY = "Q_RES","I61": #LOCATION = "R749" !CDS_LOCATION = "R749" &SEC = "1" #&CDS_SEC = "1";
"A":   PN = "1"  !CDS_PN = "1";
"B":   PN = "2"  !CDS_PN = "2";
BODY = "Q_RES","I63": #LOCATION = "R835" !CDS_LOCATION = "R835" &SEC = "1" #&CDS_SEC = "1";
"A":   PN = "1"  !CDS_PN = "1";
"B":   PN = "2"  !CDS_PN = "2";
BODY = "Q_RES","I65": LOCATION = "R319" #&CDS_LOCATION = "R319" &SEC = "1" #&CDS_SEC = "1";
"A":   PN = "1"  !CDS_PN = "1";
"B":   PN = "2"  !CDS_PN = "2";
BODY = "Q_RES","I67": #LOCATION = "R586" !CDS_LOCATION = "R586" &SEC = "1" #&CDS_SEC = "1";
"A":   PN = "1"  !CDS_PN = "1";
"B":   PN = "2"  !CDS_PN = "2";
DRAWING = "@scm_lib.scm(sch_1):page44";
BODY = "IDTQS3VH257PAG","I271": #LOCATION = "U30" !CDS_LOCATION = "U30" #SEC = "1" !CDS_SEC = "1";
"E*":   PN = "15"  !CDS_PN = "15";
"GND":   PN = "8"  !CDS_PN = "8";
"I_0A":   PN = "2"  !CDS_PN = "2";
"I_0B":   PN = "5"  !CDS_PN = "5";
"I_0C":   PN = "11"  !CDS_PN = "11";
"I_0D":   PN = "14"  !CDS_PN = "14";
"I_1A":   PN = "3"  !CDS_PN = "3";
"I_1B":   PN = "6"  !CDS_PN = "6";
"I_1C":   PN = "10"  !CDS_PN = "10";
"I_1D":   PN = "13"  !CDS_PN = "13";
"S":   PN = "1"  !CDS_PN = "1";
"VCC":   PN = "16"  !CDS_PN = "16";
"YA":   PN = "4"  !CDS_PN = "4";
"YB":   PN = "7"  !CDS_PN = "7";
"YC":   PN = "9"  !CDS_PN = "9";
"YD":   PN = "12"  !CDS_PN = "12";
BODY = "Q_CAP","I278": #LOCATION = "C255" !CDS_LOCATION = "C255" &SEC = "1" #&CDS_SEC = "1";
"A":   PN = "1"  !CDS_PN = "1";
"B":   PN = "2"  !CDS_PN = "2";
BODY = "Q_CAP","I292": #LOCATION = "C146" !CDS_LOCATION = "C146" &SEC = "1" #&CDS_SEC = "1";
"A":   PN = "1"  !CDS_PN = "1";
"B":   PN = "2"  !CDS_PN = "2";
BODY = "IDTQS3VH257PAG","I296": #LOCATION = "U21" !CDS_LOCATION = "U21" #SEC = "1" !CDS_SEC = "1";
"E*":   PN = "15"  !CDS_PN = "15";
"GND":   PN = "8"  !CDS_PN = "8";
"I_0A":   PN = "2"  !CDS_PN = "2";
"I_0B":   PN = "5"  !CDS_PN = "5";
"I_0C":   PN = "11"  !CDS_PN = "11";
"I_0D":   PN = "14"  !CDS_PN = "14";
"I_1A":   PN = "3"  !CDS_PN = "3";
"I_1B":   PN = "6"  !CDS_PN = "6";
"I_1C":   PN = "10"  !CDS_PN = "10";
"I_1D":   PN = "13"  !CDS_PN = "13";
"S":   PN = "1"  !CDS_PN = "1";
"VCC":   PN = "16"  !CDS_PN = "16";
"YA":   PN = "4"  !CDS_PN = "4";
"YB":   PN = "7"  !CDS_PN = "7";
"YC":   PN = "9"  !CDS_PN = "9";
"YD":   PN = "12"  !CDS_PN = "12";
BODY = "Q_RES","I311": #LOCATION = "R866" !CDS_LOCATION = "R866" &SEC = "1" #&CDS_SEC = "1";
"A":   PN = "1"  !CDS_PN = "1";
"B":   PN = "2"  !CDS_PN = "2";
BODY = "Q_RES","I313": #LOCATION = "R467" !CDS_LOCATION = "R467" &SEC = "1" #&CDS_SEC = "1";
"A":   PN = "1"  !CDS_PN = "1";
"B":   PN = "2"  !CDS_PN = "2";
BODY = "Q_RES","I315": #LOCATION = "R870" !CDS_LOCATION = "R870" &SEC = "1" #&CDS_SEC = "1";
"A":   PN = "1"  !CDS_PN = "1";
"B":   PN = "2"  !CDS_PN = "2";
BODY = "Q_RES","I330": #LOCATION = "R175" !CDS_LOCATION = "R175" &SEC = "1" #&CDS_SEC = "1";
"A":   PN = "1"  !CDS_PN = "1";
"B":   PN = "2"  !CDS_PN = "2";
BODY = "Q_RES","I331": #LOCATION = "R174" !CDS_LOCATION = "R174" &SEC = "1" #&CDS_SEC = "1";
"A":   PN = "1"  !CDS_PN = "1";
"B":   PN = "2"  !CDS_PN = "2";
BODY = "Q_RES","I332": #LOCATION = "R176" !CDS_LOCATION = "R176" &SEC = "1" #&CDS_SEC = "1";
"A":   PN = "1"  !CDS_PN = "1";
"B":   PN = "2"  !CDS_PN = "2";
BODY = "Q_RES","I333": #LOCATION = "R724" !CDS_LOCATION = "R724" &SEC = "1" #&CDS_SEC = "1";
"A":   PN = "1"  !CDS_PN = "1";
"B":   PN = "2"  !CDS_PN = "2";
BODY = "Q_RES","I334": #LOCATION = "R725" !CDS_LOCATION = "R725" &SEC = "1" #&CDS_SEC = "1";
"A":   PN = "1"  !CDS_PN = "1";
"B":   PN = "2"  !CDS_PN = "2";
BODY = "Q_RES","I336": #LOCATION = "R728" !CDS_LOCATION = "R728" &SEC = "1" #&CDS_SEC = "1";
"A":   PN = "1"  !CDS_PN = "1";
"B":   PN = "2"  !CDS_PN = "2";
BODY = "Q_RES","I339": #LOCATION = "R859" !CDS_LOCATION = "R859" &SEC = "1" #&CDS_SEC = "1";
"A":   PN = "1"  !CDS_PN = "1";
"B":   PN = "2"  !CDS_PN = "2";
BODY = "Q_RES","I342": #LOCATION = "R864" !CDS_LOCATION = "R864" &SEC = "1" #&CDS_SEC = "1";
"A":   PN = "1"  !CDS_PN = "1";
"B":   PN = "2"  !CDS_PN = "2";
BODY = "Q_RES","I360": #LOCATION = "R594" !CDS_LOCATION = "R594" &SEC = "1" #&CDS_SEC = "1";
"A":   PN = "1"  !CDS_PN = "1";
"B":   PN = "2"  !CDS_PN = "2";
BODY = "Q_RES","I362": #LOCATION = "R860" !CDS_LOCATION = "R860" &SEC = "1" #&CDS_SEC = "1";
"A":   PN = "1"  !CDS_PN = "1";
"B":   PN = "2"  !CDS_PN = "2";
BODY = "Q_RES","I363": #LOCATION = "R861" !CDS_LOCATION = "R861" &SEC = "1" #&CDS_SEC = "1";
"A":   PN = "1"  !CDS_PN = "1";
"B":   PN = "2"  !CDS_PN = "2";
BODY = "Q_RES","I364": #LOCATION = "R862" !CDS_LOCATION = "R862" &SEC = "1" #&CDS_SEC = "1";
"A":   PN = "1"  !CDS_PN = "1";
"B":   PN = "2"  !CDS_PN = "2";
BODY = "Q_RES","I365": #LOCATION = "R863" !CDS_LOCATION = "R863" &SEC = "1" #&CDS_SEC = "1";
"A":   PN = "1"  !CDS_PN = "1";
"B":   PN = "2"  !CDS_PN = "2";
BODY = "Q_RES","I366": #LOCATION = "R852" !CDS_LOCATION = "R852" &SEC = "1" #&CDS_SEC = "1";
"A":   PN = "1"  !CDS_PN = "1";
"B":   PN = "2"  !CDS_PN = "2";
DRAWING = "@scm_lib.scm(sch_1):page45";
BODY = "Q_RES","I19": #LOCATION = "R486" !CDS_LOCATION = "R486" &SEC = "1" #&CDS_SEC = "1";
"A":   PN = "1"  !CDS_PN = "1";
"B":   PN = "2"  !CDS_PN = "2";
BODY = "Q_RES","I20": #LOCATION = "R485" !CDS_LOCATION = "R485" &SEC = "1" #&CDS_SEC = "1";
"A":   PN = "1"  !CDS_PN = "1";
"B":   PN = "2"  !CDS_PN = "2";
BODY = "Q_RES","I21": #LOCATION = "R484" !CDS_LOCATION = "R484" &SEC = "1" #&CDS_SEC = "1";
"A":   PN = "1"  !CDS_PN = "1";
"B":   PN = "2"  !CDS_PN = "2";
BODY = "Q_RES","I22": #LOCATION = "R482" !CDS_LOCATION = "R482" &SEC = "1" #&CDS_SEC = "1";
"A":   PN = "1"  !CDS_PN = "1";
"B":   PN = "2"  !CDS_PN = "2";
BODY = "Q_RES","I23": #LOCATION = "R483" !CDS_LOCATION = "R483" &SEC = "1" #&CDS_SEC = "1";
"A":   PN = "1"  !CDS_PN = "1";
"B":   PN = "2"  !CDS_PN = "2";
BODY = "Q_RES","I24": #LOCATION = "R481" !CDS_LOCATION = "R481" &SEC = "1" #&CDS_SEC = "1";
"A":   PN = "1"  !CDS_PN = "1";
"B":   PN = "2"  !CDS_PN = "2";
BODY = "Q_RES","I33": #LOCATION = "R488" !CDS_LOCATION = "R488" &SEC = "1" #&CDS_SEC = "1";
"A":   PN = "1"  !CDS_PN = "1";
"B":   PN = "2"  !CDS_PN = "2";
BODY = "Q_RES","I34": #LOCATION = "R490" !CDS_LOCATION = "R490" &SEC = "1" #&CDS_SEC = "1";
"A":   PN = "1"  !CDS_PN = "1";
"B":   PN = "2"  !CDS_PN = "2";
BODY = "Q_RES","I35": #LOCATION = "R492" !CDS_LOCATION = "R492" &SEC = "1" #&CDS_SEC = "1";
"A":   PN = "1"  !CDS_PN = "1";
"B":   PN = "2"  !CDS_PN = "2";
BODY = "Q_CAP","I42": #LOCATION = "C244" !CDS_LOCATION = "C244" &SEC = "1" #&CDS_SEC = "1";
"A":   PN = "1"  !CDS_PN = "1";
"B":   PN = "2"  !CDS_PN = "2";
BODY = "Q_CAP","I45": #LOCATION = "C246" !CDS_LOCATION = "C246" &SEC = "1" #&CDS_SEC = "1";
"A":   PN = "1"  !CDS_PN = "1";
"B":   PN = "2"  !CDS_PN = "2";
BODY = "Q_RES","I48": #LOCATION = "R496" !CDS_LOCATION = "R496" &SEC = "1" #&CDS_SEC = "1";
"A":   PN = "1"  !CDS_PN = "1";
"B":   PN = "2"  !CDS_PN = "2";
BODY = "Q_RES","I51": #LOCATION = "R487" !CDS_LOCATION = "R487" &SEC = "1" #&CDS_SEC = "1";
"A":   PN = "1"  !CDS_PN = "1";
"B":   PN = "2"  !CDS_PN = "2";
BODY = "SCONN16_ACASPI006P06","I53": #LOCATION = "J40" !CDS_LOCATION = "J40" &SEC = "1" #&CDS_SEC = "1";
"CLK":   PN = "16"  !CDS_PN = "16";
"CS_N":   PN = "7"  !CDS_PN = "7";
"DI":   PN = "15"  !CDS_PN = "15";
"DO":   PN = "8"  !CDS_PN = "8";
"GND":   PN = "10"  !CDS_PN = "10";
"HOLD_N":   PN = "1"  !CDS_PN = "1";
"NC0":   PN = "3"  !CDS_PN = "3";
"NC1":   PN = "4"  !CDS_PN = "4";
"NC2":   PN = "5"  !CDS_PN = "5";
"NC3":   PN = "6"  !CDS_PN = "6";
"NC4":   PN = "11"  !CDS_PN = "11";
"NC6":   PN = "12"  !CDS_PN = "12";
"NC7":   PN = "13"  !CDS_PN = "13";
"NC8":   PN = "14"  !CDS_PN = "14";
"VCC":   PN = "2"  !CDS_PN = "2";
"WP_N":   PN = "9"  !CDS_PN = "9";
BODY = "MX25L51245GMI10G","I54": LOCATION = "U17" #&CDS_LOCATION = "U17" &SEC = "1" #&CDS_SEC = "1";
"CS#":   PN = "7"  !CDS_PN = "7";
"DNU1":   PN = "5"  !CDS_PN = "5";
"DNU2":   PN = "6"  !CDS_PN = "6";
"DNU3":   PN = "11"  !CDS_PN = "11";
"DNU4":   PN = "12"  !CDS_PN = "12";
"GND":   PN = "10"  !CDS_PN = "10";
"NC1":   PN = "4"  !CDS_PN = "4";
"NC2":   PN = "13"  !CDS_PN = "13";
"NC3":   PN = "14"  !CDS_PN = "14";
"NC_SIO3":   PN = "1"  !CDS_PN = "1";
"RESET#":   PN = "3"  !CDS_PN = "3";
"SCLK":   PN = "16"  !CDS_PN = "16";
"SI_SIO0":   PN = "15"  !CDS_PN = "15";
"SO_SIO1":   PN = "8"  !CDS_PN = "8";
"VCC":   PN = "2"  !CDS_PN = "2";
"WP#_SIO2":   PN = "9"  !CDS_PN = "9";
DRAWING = "@scm_lib.scm(sch_1):page46";
BODY = "SCONN11_9192031111LF","I56": #LOCATION = "J5" !CDS_LOCATION = "J5" &SEC = "1" #&CDS_SEC = "1";
"1":   PN = "1"  !CDS_PN = "1";
"2":   PN = "2"  !CDS_PN = "2";
"3":   PN = "3"  !CDS_PN = "3";
"4":   PN = "4"  !CDS_PN = "4";
"5":   PN = "5"  !CDS_PN = "5";
"6":   PN = "6"  !CDS_PN = "6";
"7":   PN = "7"  !CDS_PN = "7";
"8":   PN = "8"  !CDS_PN = "8";
"9":   PN = "9"  !CDS_PN = "9";
"10":   PN = "10"  !CDS_PN = "10";
"11":   PN = "11"  !CDS_PN = "11";
"G1":   PN = "G1"  !CDS_PN = "G1";
"G2":   PN = "G2"  !CDS_PN = "G2";
BODY = "Q_RES","I58": #LOCATION = "R501" !CDS_LOCATION = "R501" #SEC = "1" !CDS_SEC = "1";
"A":   PN = "1"  !CDS_PN = "1";
"B":   PN = "2"  !CDS_PN = "2";
BODY = "Q_RES","I60": #LOCATION = "R503" !CDS_LOCATION = "R503" #SEC = "1" !CDS_SEC = "1";
"A":   PN = "1"  !CDS_PN = "1";
"B":   PN = "2"  !CDS_PN = "2";
BODY = "Q_RES","I65": #LOCATION = "R500" !CDS_LOCATION = "R500" #SEC = "1" !CDS_SEC = "1";
"A":   PN = "1"  !CDS_PN = "1";
"B":   PN = "2"  !CDS_PN = "2";
BODY = "Q_CAP","I67": #LOCATION = "C249" !CDS_LOCATION = "C249" &SEC = "1" #&CDS_SEC = "1";
"A":   PN = "1"  !CDS_PN = "1";
"B":   PN = "2"  !CDS_PN = "2";
BODY = "Q_CAP","I69": #LOCATION = "C248" !CDS_LOCATION = "C248" &SEC = "1" #&CDS_SEC = "1";
"A":   PN = "1"  !CDS_PN = "1";
"B":   PN = "2"  !CDS_PN = "2";
BODY = "Q_RES","I74": #LOCATION = "R505" !CDS_LOCATION = "R505" &SEC = "1" #&CDS_SEC = "1";
"A":   PN = "1"  !CDS_PN = "1";
"B":   PN = "2"  !CDS_PN = "2";
BODY = "Q_RES","I75": #LOCATION = "R464" !CDS_LOCATION = "R464" &SEC = "1" #&CDS_SEC = "1";
"A":   PN = "1"  !CDS_PN = "1";
"B":   PN = "2"  !CDS_PN = "2";
BODY = "Q_RES","I78": #LOCATION = "R497" !CDS_LOCATION = "R497" &SEC = "1" #&CDS_SEC = "1";
"A":   PN = "1"  !CDS_PN = "1";
"B":   PN = "2"  !CDS_PN = "2";
BODY = "Q_RES","I98": #LOCATION = "R59" !CDS_LOCATION = "R59" &SEC = "1" #&CDS_SEC = "1";
"A":   PN = "1"  !CDS_PN = "1";
"B":   PN = "2"  !CDS_PN = "2";
BODY = "Q_CAP","I102": #LOCATION = "C144" !CDS_LOCATION = "C144" &SEC = "1" #&CDS_SEC = "1";
"A":   PN = "1"  !CDS_PN = "1";
"B":   PN = "2"  !CDS_PN = "2";
BODY = "Q_RES","I104": #LOCATION = "R50" !CDS_LOCATION = "R50" &SEC = "1" #&CDS_SEC = "1";
"A":   PN = "1"  !CDS_PN = "1";
"B":   PN = "2"  !CDS_PN = "2";
BODY = "Q_RES","I105": #LOCATION = "R113" !CDS_LOCATION = "R113" #SEC = "1" !CDS_SEC = "1";
"A":   PN = "1"  !CDS_PN = "1";
"B":   PN = "2"  !CDS_PN = "2";
BODY = "Q_RES","I106": #LOCATION = "R47" !CDS_LOCATION = "R47" &SEC = "1" #&CDS_SEC = "1";
"A":   PN = "1"  !CDS_PN = "1";
"B":   PN = "2"  !CDS_PN = "2";
BODY = "Q_CAP","I108": #LOCATION = "C143" !CDS_LOCATION = "C143" &SEC = "1" #&CDS_SEC = "1";
"A":   PN = "1"  !CDS_PN = "1";
"B":   PN = "2"  !CDS_PN = "2";
BODY = "SCONN11_9192031111LF","I113": #LOCATION = "J10" !CDS_LOCATION = "J10" &SEC = "1" #&CDS_SEC = "1";
"1":   PN = "1"  !CDS_PN = "1";
"2":   PN = "2"  !CDS_PN = "2";
"3":   PN = "3"  !CDS_PN = "3";
"4":   PN = "4"  !CDS_PN = "4";
"5":   PN = "5"  !CDS_PN = "5";
"6":   PN = "6"  !CDS_PN = "6";
"7":   PN = "7"  !CDS_PN = "7";
"8":   PN = "8"  !CDS_PN = "8";
"9":   PN = "9"  !CDS_PN = "9";
"10":   PN = "10"  !CDS_PN = "10";
"11":   PN = "11"  !CDS_PN = "11";
"G1":   PN = "G1"  !CDS_PN = "G1";
"G2":   PN = "G2"  !CDS_PN = "G2";
BODY = "Q_RES","I114": #LOCATION = "R109" !CDS_LOCATION = "R109" &SEC = "1" #&CDS_SEC = "1";
"A":   PN = "1"  !CDS_PN = "1";
"B":   PN = "2"  !CDS_PN = "2";
BODY = "Q_RES","I115": #LOCATION = "R97" !CDS_LOCATION = "R97" &SEC = "1" #&CDS_SEC = "1";
"A":   PN = "1"  !CDS_PN = "1";
"B":   PN = "2"  !CDS_PN = "2";
BODY = "Q_RES","I116": #LOCATION = "R110" !CDS_LOCATION = "R110" &SEC = "1" #&CDS_SEC = "1";
"A":   PN = "1"  !CDS_PN = "1";
"B":   PN = "2"  !CDS_PN = "2";
BODY = "Q_RES","I117": #LOCATION = "R33" !CDS_LOCATION = "R33" &SEC = "1" #&CDS_SEC = "1";
"A":   PN = "1"  !CDS_PN = "1";
"B":   PN = "2"  !CDS_PN = "2";
BODY = "Q_RES","I119": #LOCATION = "R98" !CDS_LOCATION = "R98" &SEC = "1" #&CDS_SEC = "1";
"A":   PN = "1"  !CDS_PN = "1";
"B":   PN = "2"  !CDS_PN = "2";
BODY = "Q_RES","I132": #LOCATION = "R136" !CDS_LOCATION = "R136" &SEC = "1" #&CDS_SEC = "1";
"A":   PN = "1"  !CDS_PN = "1";
"B":   PN = "2"  !CDS_PN = "2";
BODY = "Q_RES","I134": #LOCATION = "R126" !CDS_LOCATION = "R126" &SEC = "1" #&CDS_SEC = "1";
"A":   PN = "1"  !CDS_PN = "1";
"B":   PN = "2"  !CDS_PN = "2";
BODY = "Q_RES","I136": #LOCATION = "R499" !CDS_LOCATION = "R499" &SEC = "1" #&CDS_SEC = "1";
"A":   PN = "1"  !CDS_PN = "1";
"B":   PN = "2"  !CDS_PN = "2";
BODY = "Q_RES","I137": #LOCATION = "R498" !CDS_LOCATION = "R498" &SEC = "1" #&CDS_SEC = "1";
"A":   PN = "1"  !CDS_PN = "1";
"B":   PN = "2"  !CDS_PN = "2";
BODY = "Q_RES","I139": LOCATION = "R408" #&CDS_LOCATION = "R408" &SEC = "1" #&CDS_SEC = "1";
"A":   PN = "1"  !CDS_PN = "1";
"B":   PN = "2"  !CDS_PN = "2";
BODY = "Q_RES","I140": LOCATION = "R414" #&CDS_LOCATION = "R414" &SEC = "1" #&CDS_SEC = "1";
"A":   PN = "1"  !CDS_PN = "1";
"B":   PN = "2"  !CDS_PN = "2";
BODY = "Q_RES","I147": #LOCATION = "R100" !CDS_LOCATION = "R100" &SEC = "1" #&CDS_SEC = "1";
"A":   PN = "1"  !CDS_PN = "1";
"B":   PN = "2"  !CDS_PN = "2";
DRAWING = "@scm_lib.scm(sch_1):page47";
BODY = "Q_LED","I5": #LOCATION = "D7" !CDS_LOCATION = "D7" &SEC = "1" #&CDS_SEC = "1";
"A":   PN = "A"  !CDS_PN = "A";
"C":   PN = "C"  !CDS_PN = "C";
BODY = "Q_LED","I7": #LOCATION = "D0" !CDS_LOCATION = "D0" &SEC = "1" #&CDS_SEC = "1";
"A":   PN = "A"  !CDS_PN = "A";
"C":   PN = "C"  !CDS_PN = "C";
BODY = "Q_LED","I9": #LOCATION = "D1" !CDS_LOCATION = "D1" &SEC = "1" #&CDS_SEC = "1";
"A":   PN = "A"  !CDS_PN = "A";
"C":   PN = "C"  !CDS_PN = "C";
BODY = "Q_LED","I10": #LOCATION = "D4" !CDS_LOCATION = "D4" &SEC = "1" #&CDS_SEC = "1";
"A":   PN = "A"  !CDS_PN = "A";
"C":   PN = "C"  !CDS_PN = "C";
BODY = "Q_LED","I11": #LOCATION = "D2" !CDS_LOCATION = "D2" &SEC = "1" #&CDS_SEC = "1";
"A":   PN = "A"  !CDS_PN = "A";
"C":   PN = "C"  !CDS_PN = "C";
BODY = "Q_LED","I12": #LOCATION = "D5" !CDS_LOCATION = "D5" &SEC = "1" #&CDS_SEC = "1";
"A":   PN = "A"  !CDS_PN = "A";
"C":   PN = "C"  !CDS_PN = "C";
BODY = "Q_LED","I13": #LOCATION = "D3" !CDS_LOCATION = "D3" &SEC = "1" #&CDS_SEC = "1";
"A":   PN = "A"  !CDS_PN = "A";
"C":   PN = "C"  !CDS_PN = "C";
BODY = "Q_LED","I14": #LOCATION = "D6" !CDS_LOCATION = "D6" &SEC = "1" #&CDS_SEC = "1";
"A":   PN = "A"  !CDS_PN = "A";
"C":   PN = "C"  !CDS_PN = "C";
BODY = "Q_RES","I18": #LOCATION = "R597" !CDS_LOCATION = "R597" &SEC = "1" #&CDS_SEC = "1";
"A":   PN = "1"  !CDS_PN = "1";
"B":   PN = "2"  !CDS_PN = "2";
BODY = "Q_RES","I20": #LOCATION = "R598" !CDS_LOCATION = "R598" &SEC = "1" #&CDS_SEC = "1";
"A":   PN = "1"  !CDS_PN = "1";
"B":   PN = "2"  !CDS_PN = "2";
BODY = "Q_RES","I23": #LOCATION = "R599" !CDS_LOCATION = "R599" &SEC = "1" #&CDS_SEC = "1";
"A":   PN = "1"  !CDS_PN = "1";
"B":   PN = "2"  !CDS_PN = "2";
BODY = "Q_RES","I25": #LOCATION = "R600" !CDS_LOCATION = "R600" &SEC = "1" #&CDS_SEC = "1";
"A":   PN = "1"  !CDS_PN = "1";
"B":   PN = "2"  !CDS_PN = "2";
BODY = "Q_RES","I31": #LOCATION = "R601" !CDS_LOCATION = "R601" &SEC = "1" #&CDS_SEC = "1";
"A":   PN = "1"  !CDS_PN = "1";
"B":   PN = "2"  !CDS_PN = "2";
BODY = "Q_RES","I33": #LOCATION = "R602" !CDS_LOCATION = "R602" &SEC = "1" #&CDS_SEC = "1";
"A":   PN = "1"  !CDS_PN = "1";
"B":   PN = "2"  !CDS_PN = "2";
BODY = "Q_RES","I35": #LOCATION = "R603" !CDS_LOCATION = "R603" &SEC = "1" #&CDS_SEC = "1";
"A":   PN = "1"  !CDS_PN = "1";
"B":   PN = "2"  !CDS_PN = "2";
BODY = "Q_RES","I37": #LOCATION = "R604" !CDS_LOCATION = "R604" &SEC = "1" #&CDS_SEC = "1";
"A":   PN = "1"  !CDS_PN = "1";
"B":   PN = "2"  !CDS_PN = "2";
BODY = "Q_RES","I48": #LOCATION = "R669" !CDS_LOCATION = "R669" &SEC = "1" #&CDS_SEC = "1";
"A":   PN = "1"  !CDS_PN = "1";
"B":   PN = "2"  !CDS_PN = "2";
BODY = "Q_RES","I50": #LOCATION = "R674" !CDS_LOCATION = "R674" &SEC = "1" #&CDS_SEC = "1";
"A":   PN = "1"  !CDS_PN = "1";
"B":   PN = "2"  !CDS_PN = "2";
BODY = "Q_RES","I52": #LOCATION = "R676" !CDS_LOCATION = "R676" &SEC = "1" #&CDS_SEC = "1";
"A":   PN = "1"  !CDS_PN = "1";
"B":   PN = "2"  !CDS_PN = "2";
BODY = "Q_RES","I54": #LOCATION = "R695" !CDS_LOCATION = "R695" &SEC = "1" #&CDS_SEC = "1";
"A":   PN = "1"  !CDS_PN = "1";
"B":   PN = "2"  !CDS_PN = "2";
BODY = "Q_RES","I56": #LOCATION = "R696" !CDS_LOCATION = "R696" &SEC = "1" #&CDS_SEC = "1";
"A":   PN = "1"  !CDS_PN = "1";
"B":   PN = "2"  !CDS_PN = "2";
BODY = "Q_RES","I58": #LOCATION = "R697" !CDS_LOCATION = "R697" &SEC = "1" #&CDS_SEC = "1";
"A":   PN = "1"  !CDS_PN = "1";
"B":   PN = "2"  !CDS_PN = "2";
BODY = "Q_RES","I60": #LOCATION = "R698" !CDS_LOCATION = "R698" &SEC = "1" #&CDS_SEC = "1";
"A":   PN = "1"  !CDS_PN = "1";
"B":   PN = "2"  !CDS_PN = "2";
BODY = "Q_RES","I62": #LOCATION = "R700" !CDS_LOCATION = "R700" &SEC = "1" #&CDS_SEC = "1";
"A":   PN = "1"  !CDS_PN = "1";
"B":   PN = "2"  !CDS_PN = "2";
DRAWING = "@scm_lib.scm(sch_1):page49";
BODY = "MC74VHC1G32DTT1G","I5": LOCATION = "U9" #&CDS_LOCATION = "U9" &SEC = "1" #&CDS_SEC = "1";
"GND":   PN = "3"  !CDS_PN = "3";
"IN_A":   PN = "2"  !CDS_PN = "2";
"IN_B":   PN = "1"  !CDS_PN = "1";
"OUT_Y":   PN = "4"  !CDS_PN = "4";
"VCC":   PN = "5"  !CDS_PN = "5";
BODY = "MOSFET_NCH_DUAL","I6": LOCATION = "Q9" #&CDS_LOCATION = "Q9" &SEC = "1" #&CDS_SEC = "1";
"D1":   PN = "6"  !CDS_PN = "6";
"G1":   PN = "2"  !CDS_PN = "2";
"S1":   PN = "1"  !CDS_PN = "1";
BODY = "Q_RES","I8": LOCATION = "R306" #&CDS_LOCATION = "R306" &SEC = "1" #&CDS_SEC = "1";
"A":   PN = "1"  !CDS_PN = "1";
"B":   PN = "2"  !CDS_PN = "2";
BODY = "74LVC1G126SE7","I11": LOCATION = "U8" #&CDS_LOCATION = "U8" &SEC = "1" #&CDS_SEC = "1";
"A":   PN = "2"  !CDS_PN = "2";
"GND":   PN = "3"  !CDS_PN = "3";
"OE":   PN = "1"  !CDS_PN = "1";
"VCC":   PN = "5"  !CDS_PN = "5";
"Y":   PN = "4"  !CDS_PN = "4";
BODY = "Q_CAP","I13": LOCATION = "C274" #&CDS_LOCATION = "C274" &SEC = "1" #&CDS_SEC = "1";
"A":   PN = "1"  !CDS_PN = "1";
"B":   PN = "2"  !CDS_PN = "2";
BODY = "Q_RES","I22": #LOCATION = "R839" !CDS_LOCATION = "R839" &SEC = "1" #&CDS_SEC = "1";
"A":   PN = "1"  !CDS_PN = "1";
"B":   PN = "2"  !CDS_PN = "2";
BODY = "MOSFET_DUAL_6P","I24": #LOCATION = "Q12" !CDS_LOCATION = "Q12" &SEC = "1" #&CDS_SEC = "1";
"D1":   PN = "6"  !CDS_PN = "6";
"D2":   PN = "3"  !CDS_PN = "3";
"G1":   PN = "2"  !CDS_PN = "2";
"G2":   PN = "5"  !CDS_PN = "5";
"S1":   PN = "1"  !CDS_PN = "1";
"S2":   PN = "4"  !CDS_PN = "4";
BODY = "Q_RES","I26": #LOCATION = "R619" !CDS_LOCATION = "R619" &SEC = "1" #&CDS_SEC = "1";
"A":   PN = "1"  !CDS_PN = "1";
"B":   PN = "2"  !CDS_PN = "2";
BODY = "Q_RES","I34": #LOCATION = "R812" !CDS_LOCATION = "R812" &SEC = "1" #&CDS_SEC = "1";
"A":   PN = "1"  !CDS_PN = "1";
"B":   PN = "2"  !CDS_PN = "2";
BODY = "Q_RES","I35": #LOCATION = "R813" !CDS_LOCATION = "R813" &SEC = "1" #&CDS_SEC = "1";
"A":   PN = "1"  !CDS_PN = "1";
"B":   PN = "2"  !CDS_PN = "2";
BODY = "Q_RES","I36": #LOCATION = "R814" !CDS_LOCATION = "R814" &SEC = "1" #&CDS_SEC = "1";
"A":   PN = "1"  !CDS_PN = "1";
"B":   PN = "2"  !CDS_PN = "2";
BODY = "Q_CAP","I37": #LOCATION = "C324" !CDS_LOCATION = "C324" &SEC = "1" #&CDS_SEC = "1";
"A":   PN = "1"  !CDS_PN = "1";
"B":   PN = "2"  !CDS_PN = "2";
BODY = "Q_CAP","I38": #LOCATION = "C326" !CDS_LOCATION = "C326" &SEC = "1" #&CDS_SEC = "1";
"A":   PN = "1"  !CDS_PN = "1";
"B":   PN = "2"  !CDS_PN = "2";
BODY = "Q_RES","I40": #LOCATION = "R815" !CDS_LOCATION = "R815" &SEC = "1" #&CDS_SEC = "1";
"A":   PN = "1"  !CDS_PN = "1";
"B":   PN = "2"  !CDS_PN = "2";
BODY = "Q_CAP","I43": #LOCATION = "C321" !CDS_LOCATION = "C321" &SEC = "1" #&CDS_SEC = "1";
"A":   PN = "1"  !CDS_PN = "1";
"B":   PN = "2"  !CDS_PN = "2";
BODY = "Q_CAP","I45": #LOCATION = "C197" !CDS_LOCATION = "C197" &SEC = "1" #&CDS_SEC = "1";
"A":   PN = "1"  !CDS_PN = "1";
"B":   PN = "2"  !CDS_PN = "2";
BODY = "Q_LED","I50": LOCATION = "D19" #&CDS_LOCATION = "D19" &SEC = "1" #&CDS_SEC = "1";
"A":   PN = "A"  !CDS_PN = "A";
"C":   PN = "C"  !CDS_PN = "C";
BODY = "Q_LED","I51": LOCATION = "D18" #&CDS_LOCATION = "D18" &SEC = "1" #&CDS_SEC = "1";
"A":   PN = "A"  !CDS_PN = "A";
"C":   PN = "C"  !CDS_PN = "C";
BODY = "Q_RES","I59": #LOCATION = "R568" !CDS_LOCATION = "R568" &SEC = "1" #&CDS_SEC = "1";
"A":   PN = "1"  !CDS_PN = "1";
"B":   PN = "2"  !CDS_PN = "2";
BODY = "Q_RES","I60": #LOCATION = "R569" !CDS_LOCATION = "R569" &SEC = "1" #&CDS_SEC = "1";
"A":   PN = "1"  !CDS_PN = "1";
"B":   PN = "2"  !CDS_PN = "2";
BODY = "Q_CAP","I75": LOCATION = "C276" #&CDS_LOCATION = "C276" &SEC = "1" #&CDS_SEC = "1";
"A":   PN = "1"  !CDS_PN = "1";
"B":   PN = "2"  !CDS_PN = "2";
BODY = "Q_RES","I79": LOCATION = "R43" #&CDS_LOCATION = "R43" &SEC = "1" #&CDS_SEC = "1";
"A":   PN = "1"  !CDS_PN = "1";
"B":   PN = "2"  !CDS_PN = "2";
BODY = "Q_RES","I88": #LOCATION = "R283" !CDS_LOCATION = "R283" &SEC = "1" #&CDS_SEC = "1";
"A":   PN = "1"  !CDS_PN = "1";
"B":   PN = "2"  !CDS_PN = "2";
BODY = "Q_RES","I89": #LOCATION = "R284" !CDS_LOCATION = "R284" &SEC = "1" #&CDS_SEC = "1";
"A":   PN = "1"  !CDS_PN = "1";
"B":   PN = "2"  !CDS_PN = "2";
BODY = "Q_RES","I92": LOCATION = "R390" #&CDS_LOCATION = "R390" &SEC = "1" #&CDS_SEC = "1";
"A":   PN = "1"  !CDS_PN = "1";
"B":   PN = "2"  !CDS_PN = "2";
BODY = "Q_LED","I94": #LOCATION = "D14" !CDS_LOCATION = "D14" &SEC = "1" #&CDS_SEC = "1";
"A":   PN = "A"  !CDS_PN = "A";
"C":   PN = "C"  !CDS_PN = "C";
BODY = "Q_LED","I95": #LOCATION = "D15" !CDS_LOCATION = "D15" &SEC = "1" #&CDS_SEC = "1";
"A":   PN = "A"  !CDS_PN = "A";
"C":   PN = "C"  !CDS_PN = "C";
BODY = "Q_LED","I97": #LOCATION = "D13" !CDS_LOCATION = "D13" &SEC = "1" #&CDS_SEC = "1";
"A":   PN = "A"  !CDS_PN = "A";
"C":   PN = "C"  !CDS_PN = "C";
DRAWING = "@scm_lib.scm(sch_1):page50";
BODY = "Q_CAP","I43": #LOCATION = "C200" !CDS_LOCATION = "C200" &SEC = "1" #&CDS_SEC = "1";
"A":   PN = "1"  !CDS_PN = "1";
"B":   PN = "2"  !CDS_PN = "2";
BODY = "Q_CAP","I44": #LOCATION = "C198" !CDS_LOCATION = "C198" &SEC = "1" #&CDS_SEC = "1";
"A":   PN = "1"  !CDS_PN = "1";
"B":   PN = "2"  !CDS_PN = "2";
BODY = "74LVC1G17GW","I49": #LOCATION = "U32" !CDS_LOCATION = "U32" &SEC = "1" #&CDS_SEC = "1";
"A":   PN = "2"  !CDS_PN = "2";
"GND":   PN = "3"  !CDS_PN = "3";
"NC":   PN = "1"  !CDS_PN = "1";
"VCC":   PN = "5"  !CDS_PN = "5";
"Y":   PN = "4"  !CDS_PN = "4";
BODY = "Q_CAP","I51": #LOCATION = "C201" !CDS_LOCATION = "C201" &SEC = "1" #&CDS_SEC = "1";
"A":   PN = "1"  !CDS_PN = "1";
"B":   PN = "2"  !CDS_PN = "2";
BODY = "Q_CAP","I55": #LOCATION = "C199" !CDS_LOCATION = "C199" &SEC = "1" #&CDS_SEC = "1";
"A":   PN = "1"  !CDS_PN = "1";
"B":   PN = "2"  !CDS_PN = "2";
BODY = "Q_RES","I82": #LOCATION = "R504" !CDS_LOCATION = "R504" &SEC = "1" #&CDS_SEC = "1";
"A":   PN = "1"  !CDS_PN = "1";
"B":   PN = "2"  !CDS_PN = "2";
BODY = "Q_RES","I89": #LOCATION = "R768" !CDS_LOCATION = "R768" &SEC = "1" #&CDS_SEC = "1";
"A":   PN = "1"  !CDS_PN = "1";
"B":   PN = "2"  !CDS_PN = "2";
BODY = "74LVC1G07GW","I151": #LOCATION = "U31" !CDS_LOCATION = "U31" #SEC = "1" !CDS_SEC = "1";
"A":   PN = "2"  !CDS_PN = "2";
"GND":   PN = "3"  !CDS_PN = "3";
"NC":   PN = "1"  !CDS_PN = "1";
"VCC":   PN = "5"  !CDS_PN = "5";
"Y":   PN = "4"  !CDS_PN = "4";
BODY = "Q_RES","I152": #LOCATION = "R734" !CDS_LOCATION = "R734" &SEC = "1" #&CDS_SEC = "1";
"A":   PN = "1"  !CDS_PN = "1";
"B":   PN = "2"  !CDS_PN = "2";
BODY = "Q_RES","I154": #LOCATION = "R733" !CDS_LOCATION = "R733" &SEC = "1" #&CDS_SEC = "1";
"A":   PN = "1"  !CDS_PN = "1";
"B":   PN = "2"  !CDS_PN = "2";
BODY = "BAS70057F","I161": #LOCATION = "U48" !CDS_LOCATION = "U48" #SEC = "1" !CDS_SEC = "1";
"A":   PN = "2"  !CDS_PN = "2";
"B":   PN = "1"  !CDS_PN = "1";
"C":   PN = "3"  !CDS_PN = "3";
BODY = "Q_CAP","I165": #LOCATION = "C196" !CDS_LOCATION = "C196" &SEC = "1" #&CDS_SEC = "1";
"A":   PN = "1"  !CDS_PN = "1";
"B":   PN = "2"  !CDS_PN = "2";
BODY = "SW_PUSHBUTTON4P_12_G34_H2","I204": #LOCATION = "SW7" !CDS_LOCATION = "SW7" &SEC = "1" #&CDS_SEC = "1";
"1":   PN = "1"  !CDS_PN = "1";
"2":   PN = "2"  !CDS_PN = "2";
"3":   PN = "3"  !CDS_PN = "3";
"4":   PN = "4"  !CDS_PN = "4";
BODY = "Q_RES","I210": LOCATION = "R80" #&CDS_LOCATION = "R80" &SEC = "1" #&CDS_SEC = "1";
"A":   PN = "1"  !CDS_PN = "1";
"B":   PN = "2"  !CDS_PN = "2";
BODY = "Q_CAP","I212": LOCATION = "C27" #&CDS_LOCATION = "C27" &SEC = "1" #&CDS_SEC = "1";
"A":   PN = "1"  !CDS_PN = "1";
"B":   PN = "2"  !CDS_PN = "2";
BODY = "MOSFET_NCH_DUAL","I218": LOCATION = "Q13" #&CDS_LOCATION = "Q13" &SEC = "1" #&CDS_SEC = "1";
"D1":   PN = "6"  !CDS_PN = "6";
"G1":   PN = "2"  !CDS_PN = "2";
"S1":   PN = "1"  !CDS_PN = "1";
BODY = "Q_RES","I222": LOCATION = "R107" #&CDS_LOCATION = "R107" &SEC = "1" #&CDS_SEC = "1";
"A":   PN = "1"  !CDS_PN = "1";
"B":   PN = "2"  !CDS_PN = "2";
BODY = "Q_RES","I224": LOCATION = "R286" #&CDS_LOCATION = "R286" &SEC = "1" #&CDS_SEC = "1";
"A":   PN = "1"  !CDS_PN = "1";
"B":   PN = "2"  !CDS_PN = "2";
BODY = "Q_RES","I225": LOCATION = "R389" #&CDS_LOCATION = "R389" &SEC = "1" #&CDS_SEC = "1";
"A":   PN = "1"  !CDS_PN = "1";
"B":   PN = "2"  !CDS_PN = "2";
BODY = "74LVC1G07GW","I227": LOCATION = "U16" #&CDS_LOCATION = "U16" #SEC = "1" !CDS_SEC = "1";
"A":   PN = "2"  !CDS_PN = "2";
"GND":   PN = "3"  !CDS_PN = "3";
"NC":   PN = "1"  !CDS_PN = "1";
"VCC":   PN = "5"  !CDS_PN = "5";
"Y":   PN = "4"  !CDS_PN = "4";
BODY = "Q_CAP","I232": LOCATION = "C29" #&CDS_LOCATION = "C29" &SEC = "1" #&CDS_SEC = "1";
"A":   PN = "1"  !CDS_PN = "1";
"B":   PN = "2"  !CDS_PN = "2";
BODY = "Q_RES","I235": LOCATION = "R391" #&CDS_LOCATION = "R391" &SEC = "1" #&CDS_SEC = "1";
"A":   PN = "1"  !CDS_PN = "1";
"B":   PN = "2"  !CDS_PN = "2";
BODY = "Q_CAP","I236": LOCATION = "C28" #&CDS_LOCATION = "C28" &SEC = "1" #&CDS_SEC = "1";
"A":   PN = "1"  !CDS_PN = "1";
"B":   PN = "2"  !CDS_PN = "2";
BODY = "Q_RES","I241": LOCATION = "R470" #&CDS_LOCATION = "R470" &SEC = "1" #&CDS_SEC = "1";
"A":   PN = "1"  !CDS_PN = "1";
"B":   PN = "2"  !CDS_PN = "2";
BODY = "Q_RES","I242": LOCATION = "R471" #&CDS_LOCATION = "R471" &SEC = "1" #&CDS_SEC = "1";
"A":   PN = "1"  !CDS_PN = "1";
"B":   PN = "2"  !CDS_PN = "2";
BODY = "DIODE_BIDIRECTIONAL","I244": LOCATION = "D10" #&CDS_LOCATION = "D10" &SEC = "1" #&CDS_SEC = "1";
"A":   PN = "A"  !CDS_PN = "A";
"C":   PN = "C"  !CDS_PN = "C";
BODY = "Q_CAP","I246": LOCATION = "C181" #&CDS_LOCATION = "C181" &SEC = "1" #&CDS_SEC = "1";
"A":   PN = "1"  !CDS_PN = "1";
"B":   PN = "2"  !CDS_PN = "2";
BODY = "74LVC1G07GW","I278": LOCATION = "U57" #&CDS_LOCATION = "U57" #SEC = "1" !CDS_SEC = "1";
"A":   PN = "2"  !CDS_PN = "2";
"GND":   PN = "3"  !CDS_PN = "3";
"NC":   PN = "1"  !CDS_PN = "1";
"VCC":   PN = "5"  !CDS_PN = "5";
"Y":   PN = "4"  !CDS_PN = "4";
BODY = "Q_CAP","I281": LOCATION = "C336" #&CDS_LOCATION = "C336" &SEC = "1" #&CDS_SEC = "1";
"A":   PN = "1"  !CDS_PN = "1";
"B":   PN = "2"  !CDS_PN = "2";
BODY = "Q_RES","I284": LOCATION = "R883" #&CDS_LOCATION = "R883" &SEC = "1" #&CDS_SEC = "1";
"A":   PN = "1"  !CDS_PN = "1";
"B":   PN = "2"  !CDS_PN = "2";
BODY = "Q_CAP","I285": LOCATION = "C335" #&CDS_LOCATION = "C335" &SEC = "1" #&CDS_SEC = "1";
"A":   PN = "1"  !CDS_PN = "1";
"B":   PN = "2"  !CDS_PN = "2";
BODY = "Q_RES","I286": LOCATION = "R882" #&CDS_LOCATION = "R882" &SEC = "1" #&CDS_SEC = "1";
"A":   PN = "1"  !CDS_PN = "1";
"B":   PN = "2"  !CDS_PN = "2";
BODY = "SW_PUSHBUTTON4P_12_G34_H2","I292": #LOCATION = "SW6" !CDS_LOCATION = "SW6" &SEC = "1" #&CDS_SEC = "1";
"1":   PN = "1"  !CDS_PN = "1";
"2":   PN = "2"  !CDS_PN = "2";
"3":   PN = "3"  !CDS_PN = "3";
"4":   PN = "4"  !CDS_PN = "4";
BODY = "SW_PUSHBUTTON4P_12_G34_H2","I293": #LOCATION = "SW8" !CDS_LOCATION = "SW8" &SEC = "1" #&CDS_SEC = "1";
"1":   PN = "1"  !CDS_PN = "1";
"2":   PN = "2"  !CDS_PN = "2";
"3":   PN = "3"  !CDS_PN = "3";
"4":   PN = "4"  !CDS_PN = "4";
BODY = "Q_LED","I294": #LOCATION = "D21" !CDS_LOCATION = "D21" &SEC = "1" #&CDS_SEC = "1";
"A":   PN = "A"  !CDS_PN = "A";
"C":   PN = "C"  !CDS_PN = "C";
BODY = "Q_LED","I295": #LOCATION = "D22" !CDS_LOCATION = "D22" &SEC = "1" #&CDS_SEC = "1";
"A":   PN = "A"  !CDS_PN = "A";
"C":   PN = "C"  !CDS_PN = "C";
DRAWING = "@scm_lib.scm(sch_1):page51";
BODY = "Q_CAP","I1": #LOCATION = "PC205" !CDS_LOCATION = "PC205" #SEC = "1" !CDS_SEC = "1";
"A":   PN = "1"  !CDS_PN = "1";
"B":   PN = "2"  !CDS_PN = "2";
BODY = "Q_RES","I3": #LOCATION = "PR522" !CDS_LOCATION = "PR522" &SEC = "1" #&CDS_SEC = "1";
"A":   PN = "1"  !CDS_PN = "1";
"B":   PN = "2"  !CDS_PN = "2";
BODY = "Q_RES","I4": #LOCATION = "PR521" !CDS_LOCATION = "PR521" &SEC = "1" #&CDS_SEC = "1";
"A":   PN = "1"  !CDS_PN = "1";
"B":   PN = "2"  !CDS_PN = "2";
BODY = "Q_RES","I9": #LOCATION = "PR525" !CDS_LOCATION = "PR525" #SEC = "1" !CDS_SEC = "1";
"A":   PN = "1"  !CDS_PN = "1";
"B":   PN = "2"  !CDS_PN = "2";
BODY = "Q_CAP","I13": #LOCATION = "PC208" !CDS_LOCATION = "PC208" #SEC = "1" !CDS_SEC = "1";
"A":   PN = "1"  !CDS_PN = "1";
"B":   PN = "2"  !CDS_PN = "2";
BODY = "Q_RES","I21": #LOCATION = "PR241" !CDS_LOCATION = "PR241" #SEC = "1" !CDS_SEC = "1";
"A":   PN = "1"  !CDS_PN = "1";
"B":   PN = "2"  !CDS_PN = "2";
BODY = "Q_CAP","I22": #LOCATION = "PC271" !CDS_LOCATION = "PC271" &SEC = "1" #&CDS_SEC = "1";
"A":   PN = "1"  !CDS_PN = "1";
"B":   PN = "2"  !CDS_PN = "2";
BODY = "Q_CAP","I23": #LOCATION = "PC216" !CDS_LOCATION = "PC216" #SEC = "1" !CDS_SEC = "1";
"A":   PN = "1"  !CDS_PN = "1";
"B":   PN = "2"  !CDS_PN = "2";
BODY = "Q_RES","I26": #LOCATION = "PR526" !CDS_LOCATION = "PR526" &SEC = "1" #&CDS_SEC = "1";
"A":   PN = "1"  !CDS_PN = "1";
"B":   PN = "2"  !CDS_PN = "2";
BODY = "Q_CAP","I27": #LOCATION = "PC272" !CDS_LOCATION = "PC272" &SEC = "1" #&CDS_SEC = "1";
"A":   PN = "1"  !CDS_PN = "1";
"B":   PN = "2"  !CDS_PN = "2";
BODY = "Q_INDUCTOR","I28": #LOCATION = "PL34" !CDS_LOCATION = "PL34" &SEC = "1" #&CDS_SEC = "1";
"1":   PN = "1"  !CDS_PN = "1";
"2":   PN = "2"  !CDS_PN = "2";
BODY = "Q_RES","I30": #LOCATION = "PR527" !CDS_LOCATION = "PR527" &SEC = "1" #&CDS_SEC = "1";
"A":   PN = "1"  !CDS_PN = "1";
"B":   PN = "2"  !CDS_PN = "2";
BODY = "Q_CAP","I31": #LOCATION = "PC212" !CDS_LOCATION = "PC212" #SEC = "1" !CDS_SEC = "1";
"A":   PN = "1"  !CDS_PN = "1";
"B":   PN = "2"  !CDS_PN = "2";
BODY = "Q_CAP","I32": #LOCATION = "PC213" !CDS_LOCATION = "PC213" &SEC = "1" #&CDS_SEC = "1";
"A":   PN = "1"  !CDS_PN = "1";
"B":   PN = "2"  !CDS_PN = "2";
BODY = "Q_CAP","I33": #LOCATION = "PC214" !CDS_LOCATION = "PC214" &SEC = "1" #&CDS_SEC = "1";
"A":   PN = "1"  !CDS_PN = "1";
"B":   PN = "2"  !CDS_PN = "2";
BODY = "Q_CAP","I36": #LOCATION = "PC215" !CDS_LOCATION = "PC215" &SEC = "1" #&CDS_SEC = "1";
"A":   PN = "1"  !CDS_PN = "1";
"B":   PN = "2"  !CDS_PN = "2";
BODY = "Q_CAP","I37": #LOCATION = "PC217" !CDS_LOCATION = "PC217" &SEC = "1" #&CDS_SEC = "1";
"A":   PN = "1"  !CDS_PN = "1";
"B":   PN = "2"  !CDS_PN = "2";
BODY = "Q_INDUCTOR","I39": #LOCATION = "PL4" !CDS_LOCATION = "PL4" &SEC = "1" #&CDS_SEC = "1";
"1":   PN = "1"  !CDS_PN = "1";
"2":   PN = "2"  !CDS_PN = "2";
BODY = "MPQ8633AGLEC807Z","I42": #LOCATION = "PU38" !CDS_LOCATION = "PU38" &SEC = "1" #&CDS_SEC = "1";
"AGND":   PN = "2"  !CDS_PN = "2";
"BST":   PN = "1"  !CDS_PN = "1";
"CS":   PN = "3"  !CDS_PN = "3";
"EN":   PN = "8"  !CDS_PN = "8";
"FB":   PN = "7"  !CDS_PN = "7";
"MODE":   PN = "4"  !CDS_PN = "4";
"PGND":   PN = "11_18"  !CDS_PN = "11_18";
"PGOOD":   PN = "9"  !CDS_PN = "9";
"RGND":   PN = "6"  !CDS_PN = "6";
"SW":   PN = "20"  !CDS_PN = "20";
"TRK_REF":   PN = "5"  !CDS_PN = "5";
"VCC":   PN = "19"  !CDS_PN = "19";
"VIN1":   PN = "10"  !CDS_PN = "10";
"VIN2":   PN = "21"  !CDS_PN = "21";
BODY = "Q_RES","I43": #LOCATION = "PR245" !CDS_LOCATION = "PR245" &SEC = "1" #&CDS_SEC = "1";
"A":   PN = "1"  !CDS_PN = "1";
"B":   PN = "2"  !CDS_PN = "2";
BODY = "Q_CAP","I45": #LOCATION = "PC210" !CDS_LOCATION = "PC210" #SEC = "1" !CDS_SEC = "1";
"A":   PN = "1"  !CDS_PN = "1";
"B":   PN = "2"  !CDS_PN = "2";
BODY = "Q_CAP","I47": #LOCATION = "PC206" !CDS_LOCATION = "PC206" #SEC = "1" !CDS_SEC = "1";
"A":   PN = "1"  !CDS_PN = "1";
"B":   PN = "2"  !CDS_PN = "2";
BODY = "Q_CAP","I48": #LOCATION = "PC207" !CDS_LOCATION = "PC207" #SEC = "1" !CDS_SEC = "1";
"A":   PN = "1"  !CDS_PN = "1";
"B":   PN = "2"  !CDS_PN = "2";
BODY = "Q_CAP","I49": #LOCATION = "C150" !CDS_LOCATION = "C150" &SEC = "1" #&CDS_SEC = "1";
"A":   PN = "1"  !CDS_PN = "1";
"B":   PN = "2"  !CDS_PN = "2";
BODY = "Q_RES","I51": #LOCATION = "R292" !CDS_LOCATION = "R292" &SEC = "1" #&CDS_SEC = "1";
"A":   PN = "1"  !CDS_PN = "1";
"B":   PN = "2"  !CDS_PN = "2";
BODY = "Q_CAP","I52": LOCATION = "C241" #&CDS_LOCATION = "C241" &SEC = "1" #&CDS_SEC = "1";
"A":   PN = "1"  !CDS_PN = "1";
"B":   PN = "2"  !CDS_PN = "2";
BODY = "Q_RES","I54": LOCATION = "R868" #&CDS_LOCATION = "R868" &SEC = "1" #&CDS_SEC = "1";
"A":   PN = "1"  !CDS_PN = "1";
"B":   PN = "2"  !CDS_PN = "2";
BODY = "AP2205W57","I56": LOCATION = "U56" #&CDS_LOCATION = "U56" &SEC = "1" #&CDS_SEC = "1";
"ADJ||NC":   PN = "4"  !CDS_PN = "4";
"EN":   PN = "3"  !CDS_PN = "3";
"GND":   PN = "2"  !CDS_PN = "2";
"VIN":   PN = "1"  !CDS_PN = "1";
"VOUT":   PN = "5"  !CDS_PN = "5";
BODY = "Q_RES","I57": LOCATION = "R677" #&CDS_LOCATION = "R677" &SEC = "1" #&CDS_SEC = "1";
"A":   PN = "1"  !CDS_PN = "1";
"B":   PN = "2"  !CDS_PN = "2";
BODY = "Q_CAP","I60": LOCATION = "C226" #&CDS_LOCATION = "C226" &SEC = "1" #&CDS_SEC = "1";
"A":   PN = "1"  !CDS_PN = "1";
"B":   PN = "2"  !CDS_PN = "2";
BODY = "Q_RES","I62": LOCATION = "R631" #&CDS_LOCATION = "R631" &SEC = "1" #&CDS_SEC = "1";
"A":   PN = "1"  !CDS_PN = "1";
"B":   PN = "2"  !CDS_PN = "2";
BODY = "Q_CAP","I68": #LOCATION = "C227" !CDS_LOCATION = "C227" &SEC = "1" #&CDS_SEC = "1";
"A":   PN = "1"  !CDS_PN = "1";
"B":   PN = "2"  !CDS_PN = "2";
DRAWING = "@scm_lib.scm(sch_1):page52";
BODY = "Q_CAP","I9": #LOCATION = "PC221" !CDS_LOCATION = "PC221" #SEC = "1" !CDS_SEC = "1";
"A":   PN = "1"  !CDS_PN = "1";
"B":   PN = "2"  !CDS_PN = "2";
BODY = "Q_CAP","I11": #LOCATION = "PC223" !CDS_LOCATION = "PC223" #SEC = "1" !CDS_SEC = "1";
"A":   PN = "1"  !CDS_PN = "1";
"B":   PN = "2"  !CDS_PN = "2";
BODY = "Q_RES","I13": #LOCATION = "PR242" !CDS_LOCATION = "PR242" #SEC = "1" !CDS_SEC = "1";
"A":   PN = "1"  !CDS_PN = "1";
"B":   PN = "2"  !CDS_PN = "2";
BODY = "Q_CAP","I15": #LOCATION = "PC224" !CDS_LOCATION = "PC224" #SEC = "1" !CDS_SEC = "1";
"A":   PN = "1"  !CDS_PN = "1";
"B":   PN = "2"  !CDS_PN = "2";
BODY = "Q_RES","I17": #LOCATION = "PR530" !CDS_LOCATION = "PR530" &SEC = "1" #&CDS_SEC = "1";
"A":   PN = "1"  !CDS_PN = "1";
"B":   PN = "2"  !CDS_PN = "2";
BODY = "Q_CAP","I23": #LOCATION = "PC225" !CDS_LOCATION = "PC225" #SEC = "1" !CDS_SEC = "1";
"A":   PN = "1"  !CDS_PN = "1";
"B":   PN = "2"  !CDS_PN = "2";
BODY = "Q_RES","I25": #LOCATION = "PR534" !CDS_LOCATION = "PR534" &SEC = "1" #&CDS_SEC = "1";
"A":   PN = "1"  !CDS_PN = "1";
"B":   PN = "2"  !CDS_PN = "2";
BODY = "Q_INDUCTOR","I32": #LOCATION = "PL19" !CDS_LOCATION = "PL19" &SEC = "1" #&CDS_SEC = "1";
"1":   PN = "1"  !CDS_PN = "1";
"2":   PN = "2"  !CDS_PN = "2";
BODY = "Q_CAP","I35": #LOCATION = "PC226" !CDS_LOCATION = "PC226" &SEC = "1" #&CDS_SEC = "1";
"A":   PN = "1"  !CDS_PN = "1";
"B":   PN = "2"  !CDS_PN = "2";
BODY = "Q_CAP","I36": #LOCATION = "PC227" !CDS_LOCATION = "PC227" &SEC = "1" #&CDS_SEC = "1";
"A":   PN = "1"  !CDS_PN = "1";
"B":   PN = "2"  !CDS_PN = "2";
BODY = "Q_CAP","I37": #LOCATION = "PC228" !CDS_LOCATION = "PC228" &SEC = "1" #&CDS_SEC = "1";
"A":   PN = "1"  !CDS_PN = "1";
"B":   PN = "2"  !CDS_PN = "2";
BODY = "Q_CAP","I38": #LOCATION = "PC229" !CDS_LOCATION = "PC229" &SEC = "1" #&CDS_SEC = "1";
"A":   PN = "1"  !CDS_PN = "1";
"B":   PN = "2"  !CDS_PN = "2";
BODY = "Q_CAP","I63": #LOCATION = "C240" !CDS_LOCATION = "C240" &SEC = "1" #&CDS_SEC = "1";
"A":   PN = "1"  !CDS_PN = "1";
"B":   PN = "2"  !CDS_PN = "2";
BODY = "Q_CAP","I66": #LOCATION = "C251" !CDS_LOCATION = "C251" &SEC = "1" #&CDS_SEC = "1";
"A":   PN = "1"  !CDS_PN = "1";
"B":   PN = "2"  !CDS_PN = "2";
BODY = "Q_CAP","I73": #LOCATION = "C252" !CDS_LOCATION = "C252" #SEC = "1" !CDS_SEC = "1";
"A":   PN = "1"  !CDS_PN = "1";
"B":   PN = "2"  !CDS_PN = "2";
BODY = "AP22811AW57","I79": #LOCATION = "U14" !CDS_LOCATION = "U14" &SEC = "1" #&CDS_SEC = "1";
"EN":   PN = "4"  !CDS_PN = "4";
"FLG#":   PN = "3"  !CDS_PN = "3";
"GND":   PN = "2"  !CDS_PN = "2";
"IN":   PN = "5"  !CDS_PN = "5";
"OUT":   PN = "1"  !CDS_PN = "1";
BODY = "Q_CAP","I80": #LOCATION = "PC219" !CDS_LOCATION = "PC219" #SEC = "1" !CDS_SEC = "1";
"A":   PN = "1"  !CDS_PN = "1";
"B":   PN = "2"  !CDS_PN = "2";
BODY = "Q_CAP","I81": #LOCATION = "PC218" !CDS_LOCATION = "PC218" #SEC = "1" !CDS_SEC = "1";
"A":   PN = "1"  !CDS_PN = "1";
"B":   PN = "2"  !CDS_PN = "2";
BODY = "MPQ8626GDZ","I82": #LOCATION = "PU1" !CDS_LOCATION = "PU1" &SEC = "1" #&CDS_SEC = "1";
"AGND":   PN = "7"  !CDS_PN = "7";
"BST":   PN = "10"  !CDS_PN = "10";
"CS":   PN = "4"  !CDS_PN = "4";
"EN":   PN = "5"  !CDS_PN = "5";
"FB":   PN = "6"  !CDS_PN = "6";
"MODE":   PN = "12"  !CDS_PN = "12";
"PGND1":   PN = "1"  !CDS_PN = "1";
"PGND2":   PN = "14"  !CDS_PN = "14";
"PGOOD":   PN = "9"  !CDS_PN = "9";
"SW1":   PN = "2"  !CDS_PN = "2";
"SW2":   PN = "11"  !CDS_PN = "11";
"TRK_REF":   PN = "8"  !CDS_PN = "8";
"VCC":   PN = "13"  !CDS_PN = "13";
"VIN":   PN = "3"  !CDS_PN = "3";
BODY = "Q_CAP","I86": #LOCATION = "PC273" !CDS_LOCATION = "PC273" &SEC = "1" #&CDS_SEC = "1";
"A":   PN = "1"  !CDS_PN = "1";
"B":   PN = "2"  !CDS_PN = "2";
BODY = "Q_RES","I87": #LOCATION = "PR276" !CDS_LOCATION = "PR276" #SEC = "1" !CDS_SEC = "1";
"A":   PN = "1"  !CDS_PN = "1";
"B":   PN = "2"  !CDS_PN = "2";
BODY = "Q_RES","I88": #LOCATION = "PR532" !CDS_LOCATION = "PR532" &SEC = "1" #&CDS_SEC = "1";
"A":   PN = "1"  !CDS_PN = "1";
"B":   PN = "2"  !CDS_PN = "2";
BODY = "Q_CAP","I91": #LOCATION = "PC239" !CDS_LOCATION = "PC239" &SEC = "1" #&CDS_SEC = "1";
"A":   PN = "1"  !CDS_PN = "1";
"B":   PN = "2"  !CDS_PN = "2";
BODY = "Q_INDUCTOR","I92": #LOCATION = "PL35" !CDS_LOCATION = "PL35" &SEC = "1" #&CDS_SEC = "1";
"1":   PN = "1"  !CDS_PN = "1";
"2":   PN = "2"  !CDS_PN = "2";
BODY = "Q_CAP","I93": #LOCATION = "C151" !CDS_LOCATION = "C151" &SEC = "1" #&CDS_SEC = "1";
"A":   PN = "1"  !CDS_PN = "1";
"B":   PN = "2"  !CDS_PN = "2";
BODY = "Q_RES","I95": #LOCATION = "R293" !CDS_LOCATION = "R293" &SEC = "1" #&CDS_SEC = "1";
"A":   PN = "1"  !CDS_PN = "1";
"B":   PN = "2"  !CDS_PN = "2";
BODY = "Q_RES","I96": #LOCATION = "R99" !CDS_LOCATION = "R99" &SEC = "1" #&CDS_SEC = "1";
"A":   PN = "1"  !CDS_PN = "1";
"B":   PN = "2"  !CDS_PN = "2";
BODY = "Q_RES","I97": #LOCATION = "R381" !CDS_LOCATION = "R381" &SEC = "1" #&CDS_SEC = "1";
"A":   PN = "1"  !CDS_PN = "1";
"B":   PN = "2"  !CDS_PN = "2";
BODY = "Q_CAP","I101": LOCATION = "C262" #&CDS_LOCATION = "C262" &SEC = "1" #&CDS_SEC = "1";
"A":   PN = "1"  !CDS_PN = "1";
"B":   PN = "2"  !CDS_PN = "2";
BODY = "Q_CAP","I102": LOCATION = "C265" #&CDS_LOCATION = "C265" &SEC = "1" #&CDS_SEC = "1";
"A":   PN = "1"  !CDS_PN = "1";
"B":   PN = "2"  !CDS_PN = "2";
BODY = "MC74VHC1G32DTT1G","I104": LOCATION = "U42" #&CDS_LOCATION = "U42" &SEC = "1" #&CDS_SEC = "1";
"GND":   PN = "3"  !CDS_PN = "3";
"IN_A":   PN = "2"  !CDS_PN = "2";
"IN_B":   PN = "1"  !CDS_PN = "1";
"OUT_Y":   PN = "4"  !CDS_PN = "4";
"VCC":   PN = "5"  !CDS_PN = "5";
BODY = "Q_CAP","I107": LOCATION = "C297" #&CDS_LOCATION = "C297" &SEC = "1" #&CDS_SEC = "1";
"A":   PN = "1"  !CDS_PN = "1";
"B":   PN = "2"  !CDS_PN = "2";
BODY = "74LVC1G08GW","I114": LOCATION = "U18" #&CDS_LOCATION = "U18" &SEC = "1" #&CDS_SEC = "1";
"A":   PN = "2"  !CDS_PN = "2";
"B":   PN = "1"  !CDS_PN = "1";
"GND":   PN = "3"  !CDS_PN = "3";
"VCC":   PN = "5"  !CDS_PN = "5";
"Y":   PN = "4"  !CDS_PN = "4";
BODY = "Q_CAP","I119": LOCATION = "C296" #&CDS_LOCATION = "C296" &SEC = "1" #&CDS_SEC = "1";
"A":   PN = "1"  !CDS_PN = "1";
"B":   PN = "2"  !CDS_PN = "2";
BODY = "Q_CAP","I125": LOCATION = "C305" #&CDS_LOCATION = "C305" &SEC = "1" #&CDS_SEC = "1";
"A":   PN = "1"  !CDS_PN = "1";
"B":   PN = "2"  !CDS_PN = "2";
BODY = "Q_RES","I127": LOCATION = "R529" #&CDS_LOCATION = "R529" &SEC = "1" #&CDS_SEC = "1";
"A":   PN = "1"  !CDS_PN = "1";
"B":   PN = "2"  !CDS_PN = "2";
BODY = "Q_RES","I137": LOCATION = "R871" #&CDS_LOCATION = "R871" &SEC = "1" #&CDS_SEC = "1";
"A":   PN = "1"  !CDS_PN = "1";
"B":   PN = "2"  !CDS_PN = "2";
BODY = "Q_RES","I139": LOCATION = "R869" #&CDS_LOCATION = "R869" &SEC = "1" #&CDS_SEC = "1";
"A":   PN = "1"  !CDS_PN = "1";
"B":   PN = "2"  !CDS_PN = "2";
BODY = "Q_RES","I141": LOCATION = "R872" #&CDS_LOCATION = "R872" &SEC = "1" #&CDS_SEC = "1";
"A":   PN = "1"  !CDS_PN = "1";
"B":   PN = "2"  !CDS_PN = "2";
BODY = "Q_RES","I145": #LOCATION = "R709" !CDS_LOCATION = "R709" &SEC = "1" #&CDS_SEC = "1";
"A":   PN = "1"  !CDS_PN = "1";
"B":   PN = "2"  !CDS_PN = "2";
BODY = "Q_RES","I146": #LOCATION = "R415" !CDS_LOCATION = "R415" &SEC = "1" #&CDS_SEC = "1";
"A":   PN = "1"  !CDS_PN = "1";
"B":   PN = "2"  !CDS_PN = "2";
BODY = "Q_RES","I147": #LOCATION = "R380" !CDS_LOCATION = "R380" &SEC = "1" #&CDS_SEC = "1";
"A":   PN = "1"  !CDS_PN = "1";
"B":   PN = "2"  !CDS_PN = "2";
DRAWING = "@scm_lib.scm(sch_1):page53";
BODY = "Q_RES","I58": #LOCATION = "R35" !CDS_LOCATION = "R35" &SEC = "1" #&CDS_SEC = "1";
"A":   PN = "1"  !CDS_PN = "1";
"B":   PN = "2"  !CDS_PN = "2";
BODY = "RT9059GQW","I60": #LOCATION = "U39" !CDS_LOCATION = "U39" &SEC = "1" #&CDS_SEC = "1";
"ADJ":   PN = "4"  !CDS_PN = "4";
"EN":   PN = "6"  !CDS_PN = "6";
"EP":   PN = "TH"  !CDS_PN = "TH";
"PGOOD":   PN = "5"  !CDS_PN = "5";
"VDD":   PN = "10"  !CDS_PN = "10";
"VIN1":   PN = "7"  !CDS_PN = "7";
"VIN2":   PN = "8"  !CDS_PN = "8";
"VIN3":   PN = "9"  !CDS_PN = "9";
"VOUT1":   PN = "1"  !CDS_PN = "1";
"VOUT2":   PN = "2"  !CDS_PN = "2";
"VOUT3":   PN = "3"  !CDS_PN = "3";
BODY = "Q_RES","I61": #LOCATION = "R830" !CDS_LOCATION = "R830" &SEC = "1" #&CDS_SEC = "1";
"A":   PN = "1"  !CDS_PN = "1";
"B":   PN = "2"  !CDS_PN = "2";
BODY = "Q_RES","I62": #LOCATION = "R829" !CDS_LOCATION = "R829" &SEC = "1" #&CDS_SEC = "1";
"A":   PN = "1"  !CDS_PN = "1";
"B":   PN = "2"  !CDS_PN = "2";
BODY = "Q_CAP","I64": #LOCATION = "C153" !CDS_LOCATION = "C153" &SEC = "1" #&CDS_SEC = "1";
"A":   PN = "1"  !CDS_PN = "1";
"B":   PN = "2"  !CDS_PN = "2";
BODY = "Q_RES","I65": #LOCATION = "R382" !CDS_LOCATION = "R382" &SEC = "1" #&CDS_SEC = "1";
"A":   PN = "1"  !CDS_PN = "1";
"B":   PN = "2"  !CDS_PN = "2";
BODY = "Q_CAP","I67": LOCATION = "C287" #&CDS_LOCATION = "C287" &SEC = "1" #&CDS_SEC = "1";
"A":   PN = "1"  !CDS_PN = "1";
"B":   PN = "2"  !CDS_PN = "2";
BODY = "Q_RES","I68": LOCATION = "R403" #&CDS_LOCATION = "R403" &SEC = "1" #&CDS_SEC = "1";
"A":   PN = "1"  !CDS_PN = "1";
"B":   PN = "2"  !CDS_PN = "2";
BODY = "Q_CAP","I69": LOCATION = "C289" #&CDS_LOCATION = "C289" &SEC = "1" #&CDS_SEC = "1";
"A":   PN = "1"  !CDS_PN = "1";
"B":   PN = "2"  !CDS_PN = "2";
BODY = "Q_CAP","I70": LOCATION = "C291" #&CDS_LOCATION = "C291" &SEC = "1" #&CDS_SEC = "1";
"A":   PN = "1"  !CDS_PN = "1";
"B":   PN = "2"  !CDS_PN = "2";
BODY = "Q_CAP","I71": LOCATION = "C288" #&CDS_LOCATION = "C288" &SEC = "1" #&CDS_SEC = "1";
"A":   PN = "1"  !CDS_PN = "1";
"B":   PN = "2"  !CDS_PN = "2";
BODY = "Q_RES","I72": LOCATION = "R873" #&CDS_LOCATION = "R873" &SEC = "1" #&CDS_SEC = "1";
"A":   PN = "1"  !CDS_PN = "1";
"B":   PN = "2"  !CDS_PN = "2";
DRAWING = "@scm_lib.scm(sch_1):page54";
BODY = "RT9059GQW","I96": #LOCATION = "U41" !CDS_LOCATION = "U41" &SEC = "1" #&CDS_SEC = "1";
"ADJ":   PN = "4"  !CDS_PN = "4";
"EN":   PN = "6"  !CDS_PN = "6";
"EP":   PN = "TH"  !CDS_PN = "TH";
"PGOOD":   PN = "5"  !CDS_PN = "5";
"VDD":   PN = "10"  !CDS_PN = "10";
"VIN1":   PN = "7"  !CDS_PN = "7";
"VIN2":   PN = "8"  !CDS_PN = "8";
"VIN3":   PN = "9"  !CDS_PN = "9";
"VOUT1":   PN = "1"  !CDS_PN = "1";
"VOUT2":   PN = "2"  !CDS_PN = "2";
"VOUT3":   PN = "3"  !CDS_PN = "3";
BODY = "Q_RES","I97": #LOCATION = "R832" !CDS_LOCATION = "R832" &SEC = "1" #&CDS_SEC = "1";
"A":   PN = "1"  !CDS_PN = "1";
"B":   PN = "2"  !CDS_PN = "2";
BODY = "Q_RES","I98": #LOCATION = "R831" !CDS_LOCATION = "R831" &SEC = "1" #&CDS_SEC = "1";
"A":   PN = "1"  !CDS_PN = "1";
"B":   PN = "2"  !CDS_PN = "2";
BODY = "Q_RES","I99": #LOCATION = "R275" !CDS_LOCATION = "R275" &SEC = "1" #&CDS_SEC = "1";
"A":   PN = "1"  !CDS_PN = "1";
"B":   PN = "2"  !CDS_PN = "2";
BODY = "Q_CAP","I100": #LOCATION = "C154" !CDS_LOCATION = "C154" &SEC = "1" #&CDS_SEC = "1";
"A":   PN = "1"  !CDS_PN = "1";
"B":   PN = "2"  !CDS_PN = "2";
BODY = "Q_RES","I102": #LOCATION = "R393" !CDS_LOCATION = "R393" &SEC = "1" #&CDS_SEC = "1";
"A":   PN = "1"  !CDS_PN = "1";
"B":   PN = "2"  !CDS_PN = "2";
BODY = "Q_CAP","I104": LOCATION = "C142" #&CDS_LOCATION = "C142" &SEC = "1" #&CDS_SEC = "1";
"A":   PN = "1"  !CDS_PN = "1";
"B":   PN = "2"  !CDS_PN = "2";
BODY = "Q_CAP","I105": LOCATION = "C294" #&CDS_LOCATION = "C294" &SEC = "1" #&CDS_SEC = "1";
"A":   PN = "1"  !CDS_PN = "1";
"B":   PN = "2"  !CDS_PN = "2";
BODY = "Q_CAP","I106": LOCATION = "C293" #&CDS_LOCATION = "C293" &SEC = "1" #&CDS_SEC = "1";
"A":   PN = "1"  !CDS_PN = "1";
"B":   PN = "2"  !CDS_PN = "2";
BODY = "Q_CAP","I107": LOCATION = "C292" #&CDS_LOCATION = "C292" &SEC = "1" #&CDS_SEC = "1";
"A":   PN = "1"  !CDS_PN = "1";
"B":   PN = "2"  !CDS_PN = "2";
BODY = "Q_RES","I108": LOCATION = "R406" #&CDS_LOCATION = "R406" &SEC = "1" #&CDS_SEC = "1";
"A":   PN = "1"  !CDS_PN = "1";
"B":   PN = "2"  !CDS_PN = "2";
BODY = "Q_CAP","I112": LOCATION = "C298" #&CDS_LOCATION = "C298" &SEC = "1" #&CDS_SEC = "1";
"A":   PN = "1"  !CDS_PN = "1";
"B":   PN = "2"  !CDS_PN = "2";
BODY = "MC74VHC1G32DTT1G","I116": LOCATION = "U49" #&CDS_LOCATION = "U49" &SEC = "1" #&CDS_SEC = "1";
"GND":   PN = "3"  !CDS_PN = "3";
"IN_A":   PN = "2"  !CDS_PN = "2";
"IN_B":   PN = "1"  !CDS_PN = "1";
"OUT_Y":   PN = "4"  !CDS_PN = "4";
"VCC":   PN = "5"  !CDS_PN = "5";
BODY = "Q_CAP","I130": LOCATION = "C310" #&CDS_LOCATION = "C310" &SEC = "1" #&CDS_SEC = "1";
"A":   PN = "1"  !CDS_PN = "1";
"B":   PN = "2"  !CDS_PN = "2";
BODY = "Q_RES","I132": LOCATION = "R530" #&CDS_LOCATION = "R530" &SEC = "1" #&CDS_SEC = "1";
"A":   PN = "1"  !CDS_PN = "1";
"B":   PN = "2"  !CDS_PN = "2";
BODY = "Q_RES","I137": LOCATION = "R875" #&CDS_LOCATION = "R875" &SEC = "1" #&CDS_SEC = "1";
"A":   PN = "1"  !CDS_PN = "1";
"B":   PN = "2"  !CDS_PN = "2";
BODY = "Q_RES","I139": LOCATION = "R874" #&CDS_LOCATION = "R874" &SEC = "1" #&CDS_SEC = "1";
"A":   PN = "1"  !CDS_PN = "1";
"B":   PN = "2"  !CDS_PN = "2";
DRAWING = "@scm_lib.scm(sch_1):page55";
BODY = "Q_RES","I6": #LOCATION = "PR496" !CDS_LOCATION = "PR496" #SEC = "1" !CDS_SEC = "1";
"A":   PN = "1"  !CDS_PN = "1";
"B":   PN = "2"  !CDS_PN = "2";
BODY = "Q_CAP","I7": #LOCATION = "PC250" !CDS_LOCATION = "PC250" #SEC = "1" !CDS_SEC = "1";
"A":   PN = "1"  !CDS_PN = "1";
"B":   PN = "2"  !CDS_PN = "2";
BODY = "Q_RES","I8": #LOCATION = "PR539" !CDS_LOCATION = "PR539" &SEC = "1" #&CDS_SEC = "1";
"A":   PN = "1"  !CDS_PN = "1";
"B":   PN = "2"  !CDS_PN = "2";
BODY = "NB695GDZ","I15": #LOCATION = "PU41" !CDS_LOCATION = "PU41" &SEC = "1" #&CDS_SEC = "1";
"3V3":   PN = "10"  !CDS_PN = "10";
"AGND":   PN = "11"  !CDS_PN = "11";
"BST":   PN = "9"  !CDS_PN = "9";
"C0":   PN = "4"  !CDS_PN = "4";
"C1":   PN = "3"  !CDS_PN = "3";
"EN":   PN = "5"  !CDS_PN = "5";
"LP#":   PN = "6"  !CDS_PN = "6";
"MODE":   PN = "7"  !CDS_PN = "7";
"PG":   PN = "13"  !CDS_PN = "13";
"PGND":   PN = "2"  !CDS_PN = "2";
"SW":   PN = "8"  !CDS_PN = "8";
"VIN":   PN = "1"  !CDS_PN = "1";
"VOUT":   PN = "12"  !CDS_PN = "12";
BODY = "Q_CAP","I16": #LOCATION = "PC253" !CDS_LOCATION = "PC253" #SEC = "1" !CDS_SEC = "1";
"A":   PN = "1"  !CDS_PN = "1";
"B":   PN = "2"  !CDS_PN = "2";
BODY = "Q_RES","I18": #LOCATION = "PR498" !CDS_LOCATION = "PR498" #SEC = "1" !CDS_SEC = "1";
"A":   PN = "1"  !CDS_PN = "1";
"B":   PN = "2"  !CDS_PN = "2";
BODY = "Q_CAP","I19": #LOCATION = "PC254" !CDS_LOCATION = "PC254" #SEC = "1" !CDS_SEC = "1";
"A":   PN = "1"  !CDS_PN = "1";
"B":   PN = "2"  !CDS_PN = "2";
BODY = "Q_INDUCTOR","I21": #LOCATION = "PL31" !CDS_LOCATION = "PL31" &SEC = "1" #&CDS_SEC = "1";
"1":   PN = "1"  !CDS_PN = "1";
"2":   PN = "2"  !CDS_PN = "2";
BODY = "Q_CAP","I23": #LOCATION = "PC255" !CDS_LOCATION = "PC255" #SEC = "1" !CDS_SEC = "1";
"A":   PN = "1"  !CDS_PN = "1";
"B":   PN = "2"  !CDS_PN = "2";
BODY = "Q_CAP","I24": #LOCATION = "PC256" !CDS_LOCATION = "PC256" #SEC = "1" !CDS_SEC = "1";
"A":   PN = "1"  !CDS_PN = "1";
"B":   PN = "2"  !CDS_PN = "2";
BODY = "Q_CAP","I25": #LOCATION = "PC257" !CDS_LOCATION = "PC257" #SEC = "1" !CDS_SEC = "1";
"A":   PN = "1"  !CDS_PN = "1";
"B":   PN = "2"  !CDS_PN = "2";
BODY = "Q_CAP","I28": #LOCATION = "PC258" !CDS_LOCATION = "PC258" #SEC = "1" !CDS_SEC = "1";
"A":   PN = "1"  !CDS_PN = "1";
"B":   PN = "2"  !CDS_PN = "2";
BODY = "Q_CAP","I29": #LOCATION = "PC259" !CDS_LOCATION = "PC259" #SEC = "1" !CDS_SEC = "1";
"A":   PN = "1"  !CDS_PN = "1";
"B":   PN = "2"  !CDS_PN = "2";
BODY = "Q_INDUCTOR","I31": #LOCATION = "PL29" !CDS_LOCATION = "PL29" &SEC = "1" #&CDS_SEC = "1";
"1":   PN = "1"  !CDS_PN = "1";
"2":   PN = "2"  !CDS_PN = "2";
BODY = "Q_RES","I38": #LOCATION = "R708" !CDS_LOCATION = "R708" &SEC = "1" #&CDS_SEC = "1";
"A":   PN = "1"  !CDS_PN = "1";
"B":   PN = "2"  !CDS_PN = "2";
BODY = "Q_RES","I41": #LOCATION = "R764" !CDS_LOCATION = "R764" &SEC = "1" #&CDS_SEC = "1";
"A":   PN = "1"  !CDS_PN = "1";
"B":   PN = "2"  !CDS_PN = "2";
BODY = "Q_CAP","I42": #LOCATION = "PC252" !CDS_LOCATION = "PC252" &SEC = "1" #&CDS_SEC = "1";
"A":   PN = "1"  !CDS_PN = "1";
"B":   PN = "2"  !CDS_PN = "2";
BODY = "Q_CAP","I43": #LOCATION = "PC251" !CDS_LOCATION = "PC251" &SEC = "1" #&CDS_SEC = "1";
"A":   PN = "1"  !CDS_PN = "1";
"B":   PN = "2"  !CDS_PN = "2";
BODY = "Q_RES","I45": #LOCATION = "PR274" !CDS_LOCATION = "PR274" &SEC = "1" #&CDS_SEC = "1";
"A":   PN = "1"  !CDS_PN = "1";
"B":   PN = "2"  !CDS_PN = "2";
BODY = "Q_RES","I48": #LOCATION = "PR275" !CDS_LOCATION = "PR275" &SEC = "1" #&CDS_SEC = "1";
"A":   PN = "1"  !CDS_PN = "1";
"B":   PN = "2"  !CDS_PN = "2";
BODY = "Q_RES","I50": #LOCATION = "R276" !CDS_LOCATION = "R276" &SEC = "1" #&CDS_SEC = "1";
"A":   PN = "1"  !CDS_PN = "1";
"B":   PN = "2"  !CDS_PN = "2";
BODY = "Q_CAP","I52": #LOCATION = "C155" !CDS_LOCATION = "C155" &SEC = "1" #&CDS_SEC = "1";
"A":   PN = "1"  !CDS_PN = "1";
"B":   PN = "2"  !CDS_PN = "2";
BODY = "Q_CAP","I54": LOCATION = "C278" #&CDS_LOCATION = "C278" &SEC = "1" #&CDS_SEC = "1";
"A":   PN = "1"  !CDS_PN = "1";
"B":   PN = "2"  !CDS_PN = "2";
BODY = "Q_CAP","I61": LOCATION = "C301" #&CDS_LOCATION = "C301" &SEC = "1" #&CDS_SEC = "1";
"A":   PN = "1"  !CDS_PN = "1";
"B":   PN = "2"  !CDS_PN = "2";
BODY = "74LVC1G08GW","I63": LOCATION = "U52" #&CDS_LOCATION = "U52" &SEC = "1" #&CDS_SEC = "1";
"A":   PN = "2"  !CDS_PN = "2";
"B":   PN = "1"  !CDS_PN = "1";
"GND":   PN = "3"  !CDS_PN = "3";
"VCC":   PN = "5"  !CDS_PN = "5";
"Y":   PN = "4"  !CDS_PN = "4";
BODY = "Q_RES","I68": LOCATION = "R876" #&CDS_LOCATION = "R876" &SEC = "1" #&CDS_SEC = "1";
"A":   PN = "1"  !CDS_PN = "1";
"B":   PN = "2"  !CDS_PN = "2";
BODY = "Q_RES","I70": LOCATION = "R877" #&CDS_LOCATION = "R877" &SEC = "1" #&CDS_SEC = "1";
"A":   PN = "1"  !CDS_PN = "1";
"B":   PN = "2"  !CDS_PN = "2";
DRAWING = "@scm_lib.scm(sch_1):page56";
BODY = "Q_CAP","I7": #LOCATION = "PC260" !CDS_LOCATION = "PC260" #SEC = "1" !CDS_SEC = "1";
"A":   PN = "1"  !CDS_PN = "1";
"B":   PN = "2"  !CDS_PN = "2";
BODY = "Q_RES","I8": #LOCATION = "PR541" !CDS_LOCATION = "PR541" &SEC = "1" #&CDS_SEC = "1";
"A":   PN = "1"  !CDS_PN = "1";
"B":   PN = "2"  !CDS_PN = "2";
BODY = "NB695GDZ","I15": #LOCATION = "PU42" !CDS_LOCATION = "PU42" &SEC = "1" #&CDS_SEC = "1";
"3V3":   PN = "10"  !CDS_PN = "10";
"AGND":   PN = "11"  !CDS_PN = "11";
"BST":   PN = "9"  !CDS_PN = "9";
"C0":   PN = "4"  !CDS_PN = "4";
"C1":   PN = "3"  !CDS_PN = "3";
"EN":   PN = "5"  !CDS_PN = "5";
"LP#":   PN = "6"  !CDS_PN = "6";
"MODE":   PN = "7"  !CDS_PN = "7";
"PG":   PN = "13"  !CDS_PN = "13";
"PGND":   PN = "2"  !CDS_PN = "2";
"SW":   PN = "8"  !CDS_PN = "8";
"VIN":   PN = "1"  !CDS_PN = "1";
"VOUT":   PN = "12"  !CDS_PN = "12";
BODY = "Q_CAP","I16": #LOCATION = "PC263" !CDS_LOCATION = "PC263" #SEC = "1" !CDS_SEC = "1";
"A":   PN = "1"  !CDS_PN = "1";
"B":   PN = "2"  !CDS_PN = "2";
BODY = "Q_RES","I18": #LOCATION = "PR500" !CDS_LOCATION = "PR500" #SEC = "1" !CDS_SEC = "1";
"A":   PN = "1"  !CDS_PN = "1";
"B":   PN = "2"  !CDS_PN = "2";
BODY = "Q_CAP","I19": #LOCATION = "PC264" !CDS_LOCATION = "PC264" #SEC = "1" !CDS_SEC = "1";
"A":   PN = "1"  !CDS_PN = "1";
"B":   PN = "2"  !CDS_PN = "2";
BODY = "Q_CAP","I23": #LOCATION = "PC266" !CDS_LOCATION = "PC266" #SEC = "1" !CDS_SEC = "1";
"A":   PN = "1"  !CDS_PN = "1";
"B":   PN = "2"  !CDS_PN = "2";
BODY = "Q_CAP","I24": #LOCATION = "PC267" !CDS_LOCATION = "PC267" #SEC = "1" !CDS_SEC = "1";
"A":   PN = "1"  !CDS_PN = "1";
"B":   PN = "2"  !CDS_PN = "2";
BODY = "Q_CAP","I25": #LOCATION = "PC268" !CDS_LOCATION = "PC268" #SEC = "1" !CDS_SEC = "1";
"A":   PN = "1"  !CDS_PN = "1";
"B":   PN = "2"  !CDS_PN = "2";
BODY = "Q_CAP","I28": #LOCATION = "PC269" !CDS_LOCATION = "PC269" #SEC = "1" !CDS_SEC = "1";
"A":   PN = "1"  !CDS_PN = "1";
"B":   PN = "2"  !CDS_PN = "2";
BODY = "Q_CAP","I29": #LOCATION = "PC270" !CDS_LOCATION = "PC270" #SEC = "1" !CDS_SEC = "1";
"A":   PN = "1"  !CDS_PN = "1";
"B":   PN = "2"  !CDS_PN = "2";
BODY = "Q_INDUCTOR","I34": #LOCATION = "PL32" !CDS_LOCATION = "PL32" &SEC = "1" #&CDS_SEC = "1";
"1":   PN = "1"  !CDS_PN = "1";
"2":   PN = "2"  !CDS_PN = "2";
BODY = "Q_INDUCTOR","I37": #LOCATION = "PL33" !CDS_LOCATION = "PL33" &SEC = "1" #&CDS_SEC = "1";
"1":   PN = "1"  !CDS_PN = "1";
"2":   PN = "2"  !CDS_PN = "2";
BODY = "Q_CAP","I43": #LOCATION = "PC262" !CDS_LOCATION = "PC262" &SEC = "1" #&CDS_SEC = "1";
"A":   PN = "1"  !CDS_PN = "1";
"B":   PN = "2"  !CDS_PN = "2";
BODY = "Q_CAP","I44": #LOCATION = "PC261" !CDS_LOCATION = "PC261" &SEC = "1" #&CDS_SEC = "1";
"A":   PN = "1"  !CDS_PN = "1";
"B":   PN = "2"  !CDS_PN = "2";
BODY = "Q_RES","I47": #LOCATION = "PR193" !CDS_LOCATION = "PR193" &SEC = "1" #&CDS_SEC = "1";
"A":   PN = "1"  !CDS_PN = "1";
"B":   PN = "2"  !CDS_PN = "2";
BODY = "Q_RES","I48": #LOCATION = "PR205" !CDS_LOCATION = "PR205" &SEC = "1" #&CDS_SEC = "1";
"A":   PN = "1"  !CDS_PN = "1";
"B":   PN = "2"  !CDS_PN = "2";
BODY = "Q_CAP","I51": #LOCATION = "C156" !CDS_LOCATION = "C156" &SEC = "1" #&CDS_SEC = "1";
"A":   PN = "1"  !CDS_PN = "1";
"B":   PN = "2"  !CDS_PN = "2";
BODY = "Q_RES","I54": #LOCATION = "R277" !CDS_LOCATION = "R277" &SEC = "1" #&CDS_SEC = "1";
"A":   PN = "1"  !CDS_PN = "1";
"B":   PN = "2"  !CDS_PN = "2";
BODY = "Q_RES","I55": #LOCATION = "R399" !CDS_LOCATION = "R399" &SEC = "1" #&CDS_SEC = "1";
"A":   PN = "1"  !CDS_PN = "1";
"B":   PN = "2"  !CDS_PN = "2";
BODY = "Q_CAP","I58": LOCATION = "C280" #&CDS_LOCATION = "C280" &SEC = "1" #&CDS_SEC = "1";
"A":   PN = "1"  !CDS_PN = "1";
"B":   PN = "2"  !CDS_PN = "2";
BODY = "Q_CAP","I64": LOCATION = "C302" #&CDS_LOCATION = "C302" &SEC = "1" #&CDS_SEC = "1";
"A":   PN = "1"  !CDS_PN = "1";
"B":   PN = "2"  !CDS_PN = "2";
BODY = "74LVC1G08GW","I66": LOCATION = "U53" #&CDS_LOCATION = "U53" &SEC = "1" #&CDS_SEC = "1";
"A":   PN = "2"  !CDS_PN = "2";
"B":   PN = "1"  !CDS_PN = "1";
"GND":   PN = "3"  !CDS_PN = "3";
"VCC":   PN = "5"  !CDS_PN = "5";
"Y":   PN = "4"  !CDS_PN = "4";
BODY = "Q_RES","I71": #LOCATION = "PR543" !CDS_LOCATION = "PR543" &SEC = "1" #&CDS_SEC = "1";
"A":   PN = "1"  !CDS_PN = "1";
"B":   PN = "2"  !CDS_PN = "2";
BODY = "Q_RES","I72": LOCATION = "R878" #&CDS_LOCATION = "R878" &SEC = "1" #&CDS_SEC = "1";
"A":   PN = "1"  !CDS_PN = "1";
"B":   PN = "2"  !CDS_PN = "2";
DRAWING = "@scm_lib.scm(sch_1):page57";
BODY = "HOLE","I14": #LOCATION = "H2B1" !CDS_LOCATION = "H2B1" &SEC = "1" #&CDS_SEC = "1";
"1":   PN = "1"  !CDS_PN = "1";
BODY = "HOLE","I34": #LOCATION = "H2B2" !CDS_LOCATION = "H2B2" &SEC = "1" #&CDS_SEC = "1";
"1":   PN = "1"  !CDS_PN = "1";
BODY = "HOLE","I35": #LOCATION = "H5" !CDS_LOCATION = "H5" &SEC = "1" #&CDS_SEC = "1";
"1":   PN = "1"  !CDS_PN = "1";
BODY = "HOLE","I36": #LOCATION = "H9" !CDS_LOCATION = "H9" &SEC = "1" #&CDS_SEC = "1";
"1":   PN = "1"  !CDS_PN = "1";
BODY = "HOLE","I38": LOCATION = "H3" #&CDS_LOCATION = "H3" &SEC = "1" #&CDS_SEC = "1";
"1":   PN = "1"  !CDS_PN = "1";
BODY = "HOLE","I40": LOCATION = "H4" #&CDS_LOCATION = "H4" &SEC = "1" #&CDS_SEC = "1";
"1":   PN = "1"  !CDS_PN = "1";
BODY = "HOLE","I45": LOCATION = "H2" #&CDS_LOCATION = "H2" &SEC = "1" #&CDS_SEC = "1";
"1":   PN = "1"  !CDS_PN = "1";
BODY = "HOLE","I49": #LOCATION = "H1" !CDS_LOCATION = "H1" &SEC = "1" #&CDS_SEC = "1";
"1":   PN = "1"  !CDS_PN = "1";
BODY = "HOLE","I50": #LOCATION = "H6" !CDS_LOCATION = "H6" &SEC = "1" #&CDS_SEC = "1";
"1":   PN = "1"  !CDS_PN = "1";
BODY = "HOLE","I51": #LOCATION = "H7" !CDS_LOCATION = "H7" &SEC = "1" #&CDS_SEC = "1";
"1":   PN = "1"  !CDS_PN = "1";
DRAWING = "@scm_lib.scm(sch_1):page59";
BODY = "ME_DUMMY_SYMBOL","I27": LOCATION = "ME1" #&CDS_LOCATION = "ME1";
BODY = "ME_DUMMY_SYMBOL","I28": LOCATION = "ME2" #&CDS_LOCATION = "ME2";
BODY = "ME_DUMMY_SYMBOL","I29": #LOCATION = "DM7" !CDS_LOCATION = "DM7";
BODY = "ME_DUMMY_SYMBOL","I34": LOCATION = "ME4" #&CDS_LOCATION = "ME4";
BODY = "DUMMY_SYMBOL","I35": LOCATION = "DM3" #&CDS_LOCATION = "DM3" &SEC = "1" #&CDS_SEC = "1";
"1":   PN = "1"  !CDS_PN = "1";
BODY = "DUMMY_SYMBOL","I36": LOCATION = "DM1" #&CDS_LOCATION = "DM1" &SEC = "1" #&CDS_SEC = "1";
"1":   PN = "1"  !CDS_PN = "1";
BODY = "DUMMY_SYMBOL","I37": LOCATION = "DM2" #&CDS_LOCATION = "DM2" &SEC = "1" #&CDS_SEC = "1";
"1":   PN = "1"  !CDS_PN = "1";
DRAWING = "@scm_lib.scm(sch_1):page60";
BODY = "TDR_3P","I1": #LOCATION = "DB1" !CDS_LOCATION = "DB1" #SEC = "1" !CDS_SEC = "1";
"GND":   PN = "1"  !CDS_PN = "1";
"IO1":   PN = "2"  !CDS_PN = "2";
"IO2":   PN = "3"  !CDS_PN = "3";
BODY = "TDR_3P","I3": #LOCATION = "DB6" !CDS_LOCATION = "DB6" #SEC = "1" !CDS_SEC = "1";
"GND":   PN = "1"  !CDS_PN = "1";
"IO1":   PN = "2"  !CDS_PN = "2";
"IO2":   PN = "3"  !CDS_PN = "3";
BODY = "TDR_3P","I5": #LOCATION = "DB5" !CDS_LOCATION = "DB5" #SEC = "1" !CDS_SEC = "1";
"GND":   PN = "1"  !CDS_PN = "1";
"IO1":   PN = "2"  !CDS_PN = "2";
"IO2":   PN = "3"  !CDS_PN = "3";
BODY = "TDR_3P","I7": #LOCATION = "DB4" !CDS_LOCATION = "DB4" #SEC = "1" !CDS_SEC = "1";
"GND":   PN = "1"  !CDS_PN = "1";
"IO1":   PN = "2"  !CDS_PN = "2";
"IO2":   PN = "3"  !CDS_PN = "3";
BODY = "TDR_3P","I9": #LOCATION = "DB3" !CDS_LOCATION = "DB3" #SEC = "1" !CDS_SEC = "1";
"GND":   PN = "1"  !CDS_PN = "1";
"IO1":   PN = "2"  !CDS_PN = "2";
"IO2":   PN = "3"  !CDS_PN = "3";
BODY = "TDR_3P","I11": #LOCATION = "DB2" !CDS_LOCATION = "DB2" #SEC = "1" !CDS_SEC = "1";
"GND":   PN = "1"  !CDS_PN = "1";
"IO1":   PN = "2"  !CDS_PN = "2";
"IO2":   PN = "3"  !CDS_PN = "3";
BODY = "TP_TDR_4P_FTS","I13": #LOCATION = "X1" !CDS_LOCATION = "X1" #SEC = "1" !CDS_SEC = "1";
"P1":   PN = "2"  !CDS_PN = "2";
"P2":   PN = "3"  !CDS_PN = "3";
"S1":   PN = "1"  !CDS_PN = "1";
"S2":   PN = "4"  !CDS_PN = "4";
BODY = "TP_TDR_4P_FTS","I14": #LOCATION = "X7" !CDS_LOCATION = "X7" #SEC = "1" !CDS_SEC = "1";
"P1":   PN = "2"  !CDS_PN = "2";
"P2":   PN = "3"  !CDS_PN = "3";
"S1":   PN = "1"  !CDS_PN = "1";
"S2":   PN = "4"  !CDS_PN = "4";
BODY = "TP_TDR_4P_FTS","I18": #LOCATION = "X12" !CDS_LOCATION = "X12" #SEC = "1" !CDS_SEC = "1";
"P1":   PN = "2"  !CDS_PN = "2";
"P2":   PN = "3"  !CDS_PN = "3";
"S1":   PN = "1"  !CDS_PN = "1";
"S2":   PN = "4"  !CDS_PN = "4";
BODY = "TP_TDR_4P_FTS","I19": #LOCATION = "X6" !CDS_LOCATION = "X6" #SEC = "1" !CDS_SEC = "1";
"P1":   PN = "2"  !CDS_PN = "2";
"P2":   PN = "3"  !CDS_PN = "3";
"S1":   PN = "1"  !CDS_PN = "1";
"S2":   PN = "4"  !CDS_PN = "4";
BODY = "TP_TDR_4P_FTS","I22": #LOCATION = "X11" !CDS_LOCATION = "X11" #SEC = "1" !CDS_SEC = "1";
"P1":   PN = "2"  !CDS_PN = "2";
"P2":   PN = "3"  !CDS_PN = "3";
"S1":   PN = "1"  !CDS_PN = "1";
"S2":   PN = "4"  !CDS_PN = "4";
BODY = "TP_TDR_4P_FTS","I23": #LOCATION = "X5" !CDS_LOCATION = "X5" #SEC = "1" !CDS_SEC = "1";
"P1":   PN = "2"  !CDS_PN = "2";
"P2":   PN = "3"  !CDS_PN = "3";
"S1":   PN = "1"  !CDS_PN = "1";
"S2":   PN = "4"  !CDS_PN = "4";
BODY = "TP_TDR_4P_FTS","I34": #LOCATION = "X8" !CDS_LOCATION = "X8" #SEC = "1" !CDS_SEC = "1";
"P1":   PN = "2"  !CDS_PN = "2";
"P2":   PN = "3"  !CDS_PN = "3";
"S1":   PN = "1"  !CDS_PN = "1";
"S2":   PN = "4"  !CDS_PN = "4";
BODY = "TP_TDR_4P_FTS","I35": #LOCATION = "X2" !CDS_LOCATION = "X2" #SEC = "1" !CDS_SEC = "1";
"P1":   PN = "2"  !CDS_PN = "2";
"P2":   PN = "3"  !CDS_PN = "3";
"S1":   PN = "1"  !CDS_PN = "1";
"S2":   PN = "4"  !CDS_PN = "4";
BODY = "TP_TDR_4P_FTS","I38": #LOCATION = "X19" !CDS_LOCATION = "X19" #SEC = "1" !CDS_SEC = "1";
"P1":   PN = "2"  !CDS_PN = "2";
"P2":   PN = "3"  !CDS_PN = "3";
"S1":   PN = "1"  !CDS_PN = "1";
"S2":   PN = "4"  !CDS_PN = "4";
BODY = "TP_TDR_4P_FTS","I39": #LOCATION = "X13" !CDS_LOCATION = "X13" #SEC = "1" !CDS_SEC = "1";
"P1":   PN = "2"  !CDS_PN = "2";
"P2":   PN = "3"  !CDS_PN = "3";
"S1":   PN = "1"  !CDS_PN = "1";
"S2":   PN = "4"  !CDS_PN = "4";
BODY = "TP_TDR_4P_FTS","I42": #LOCATION = "X18" !CDS_LOCATION = "X18" #SEC = "1" !CDS_SEC = "1";
"P1":   PN = "2"  !CDS_PN = "2";
"P2":   PN = "3"  !CDS_PN = "3";
"S1":   PN = "1"  !CDS_PN = "1";
"S2":   PN = "4"  !CDS_PN = "4";
BODY = "TP_TDR_4P_FTS","I43": #LOCATION = "X24" !CDS_LOCATION = "X24" #SEC = "1" !CDS_SEC = "1";
"P1":   PN = "2"  !CDS_PN = "2";
"P2":   PN = "3"  !CDS_PN = "3";
"S1":   PN = "1"  !CDS_PN = "1";
"S2":   PN = "4"  !CDS_PN = "4";
BODY = "TP_TDR_4P_FTS","I46": #LOCATION = "X17" !CDS_LOCATION = "X17" #SEC = "1" !CDS_SEC = "1";
"P1":   PN = "2"  !CDS_PN = "2";
"P2":   PN = "3"  !CDS_PN = "3";
"S1":   PN = "1"  !CDS_PN = "1";
"S2":   PN = "4"  !CDS_PN = "4";
BODY = "TP_TDR_4P_FTS","I47": #LOCATION = "X23" !CDS_LOCATION = "X23" #SEC = "1" !CDS_SEC = "1";
"P1":   PN = "2"  !CDS_PN = "2";
"P2":   PN = "3"  !CDS_PN = "3";
"S1":   PN = "1"  !CDS_PN = "1";
"S2":   PN = "4"  !CDS_PN = "4";
BODY = "TP_TDR_4P_FTS","I58": #LOCATION = "X14" !CDS_LOCATION = "X14" #SEC = "1" !CDS_SEC = "1";
"P1":   PN = "2"  !CDS_PN = "2";
"P2":   PN = "3"  !CDS_PN = "3";
"S1":   PN = "1"  !CDS_PN = "1";
"S2":   PN = "4"  !CDS_PN = "4";
BODY = "TP_TDR_4P_FTS","I59": #LOCATION = "X20" !CDS_LOCATION = "X20" #SEC = "1" !CDS_SEC = "1";
"P1":   PN = "2"  !CDS_PN = "2";
"P2":   PN = "3"  !CDS_PN = "3";
"S1":   PN = "1"  !CDS_PN = "1";
"S2":   PN = "4"  !CDS_PN = "4";
DRAWING = "@scm_lib.scm(sch_1):page48";
BODY = "Q_RES","I33": LOCATION = "R615" #&CDS_LOCATION = "R615" &SEC = "1" #&CDS_SEC = "1";
"A":   PN = "1"  !CDS_PN = "1";
"B":   PN = "2"  !CDS_PN = "2";
BODY = "Q_RES","I39": #LOCATION = "R620" !CDS_LOCATION = "R620" &SEC = "1" #&CDS_SEC = "1";
"A":   PN = "1"  !CDS_PN = "1";
"B":   PN = "2"  !CDS_PN = "2";
BODY = "Q_RES","I40": #LOCATION = "R616" !CDS_LOCATION = "R616" &SEC = "1" #&CDS_SEC = "1";
"A":   PN = "1"  !CDS_PN = "1";
"B":   PN = "2"  !CDS_PN = "2";
BODY = "Q_RES","I42": LOCATION = "R881" #&CDS_LOCATION = "R881" &SEC = "1" #&CDS_SEC = "1";
"A":   PN = "1"  !CDS_PN = "1";
"B":   PN = "2"  !CDS_PN = "2";
BODY = "Q_RES","I48": #LOCATION = "R624" !CDS_LOCATION = "R624" &SEC = "1" #&CDS_SEC = "1";
"A":   PN = "1"  !CDS_PN = "1";
"B":   PN = "2"  !CDS_PN = "2";
BODY = "Q_RES","I50": #LOCATION = "R509" !CDS_LOCATION = "R509" &SEC = "1" #&CDS_SEC = "1";
"A":   PN = "1"  !CDS_PN = "1";
"B":   PN = "2"  !CDS_PN = "2";
BODY = "Q_RES","I51": #LOCATION = "R508" !CDS_LOCATION = "R508" &SEC = "1" #&CDS_SEC = "1";
"A":   PN = "1"  !CDS_PN = "1";
"B":   PN = "2"  !CDS_PN = "2";
BODY = "Q_RES","I52": #LOCATION = "R507" !CDS_LOCATION = "R507" &SEC = "1" #&CDS_SEC = "1";
"A":   PN = "1"  !CDS_PN = "1";
"B":   PN = "2"  !CDS_PN = "2";
BODY = "Q_RES","I53": #LOCATION = "R506" !CDS_LOCATION = "R506" &SEC = "1" #&CDS_SEC = "1";
"A":   PN = "1"  !CDS_PN = "1";
"B":   PN = "2"  !CDS_PN = "2";
BODY = "Q_RES","I56": #LOCATION = "R431" !CDS_LOCATION = "R431" &SEC = "1" #&CDS_SEC = "1";
"A":   PN = "1"  !CDS_PN = "1";
"B":   PN = "2"  !CDS_PN = "2";
DRAWING = "@scm_lib.scm(sch_1):page58";
BODY = "PICOPROBE_BXA","I55": #LOCATION = "J9" !CDS_LOCATION = "J9" &SEC = "1" #&CDS_SEC = "1";
"1_P":   PN = "1"  !CDS_PN = "1";
"2_N":   PN = "2"  !CDS_PN = "2";
"3_G":   PN = "3"  !CDS_PN = "3";
BODY = "PICOPROBE_BXA","I57": #LOCATION = "J11" !CDS_LOCATION = "J11" &SEC = "1" #&CDS_SEC = "1";
"1_P":   PN = "1"  !CDS_PN = "1";
"2_N":   PN = "2"  !CDS_PN = "2";
"3_G":   PN = "3"  !CDS_PN = "3";
BODY = "PICOPROBE_BXA","I58": #LOCATION = "J16" !CDS_LOCATION = "J16" &SEC = "1" #&CDS_SEC = "1";
"1_P":   PN = "1"  !CDS_PN = "1";
"2_N":   PN = "2"  !CDS_PN = "2";
"3_G":   PN = "3"  !CDS_PN = "3";
BODY = "PICOPROBE_BXA","I59": #LOCATION = "J17" !CDS_LOCATION = "J17" &SEC = "1" #&CDS_SEC = "1";
"1_P":   PN = "1"  !CDS_PN = "1";
"2_N":   PN = "2"  !CDS_PN = "2";
"3_G":   PN = "3"  !CDS_PN = "3";
BODY = "PICOPROBE_BXA","I60": #LOCATION = "J25" !CDS_LOCATION = "J25" &SEC = "1" #&CDS_SEC = "1";
"1_P":   PN = "1"  !CDS_PN = "1";
"2_N":   PN = "2"  !CDS_PN = "2";
"3_G":   PN = "3"  !CDS_PN = "3";
BODY = "PICOPROBE_BXA","I61": #LOCATION = "J28" !CDS_LOCATION = "J28" &SEC = "1" #&CDS_SEC = "1";
"1_P":   PN = "1"  !CDS_PN = "1";
"2_N":   PN = "2"  !CDS_PN = "2";
"3_G":   PN = "3"  !CDS_PN = "3";
BODY = "PICOPROBE_BXA","I62": #LOCATION = "J26" !CDS_LOCATION = "J26" &SEC = "1" #&CDS_SEC = "1";
"1_P":   PN = "1"  !CDS_PN = "1";
"2_N":   PN = "2"  !CDS_PN = "2";
"3_G":   PN = "3"  !CDS_PN = "3";
BODY = "PICOPROBE_BXA","I63": #LOCATION = "J27" !CDS_LOCATION = "J27" &SEC = "1" #&CDS_SEC = "1";
"1_P":   PN = "1"  !CDS_PN = "1";
"2_N":   PN = "2"  !CDS_PN = "2";
"3_G":   PN = "3"  !CDS_PN = "3";
BODY = "PICOPROBE_BXA","I64": #LOCATION = "J12" !CDS_LOCATION = "J12" &SEC = "1" #&CDS_SEC = "1";
"1_P":   PN = "1"  !CDS_PN = "1";
"2_N":   PN = "2"  !CDS_PN = "2";
"3_G":   PN = "3"  !CDS_PN = "3";
BODY = "PICOPROBE_BXA","I65": #LOCATION = "J29" !CDS_LOCATION = "J29" &SEC = "1" #&CDS_SEC = "1";
"1_P":   PN = "1"  !CDS_PN = "1";
"2_N":   PN = "2"  !CDS_PN = "2";
"3_G":   PN = "3"  !CDS_PN = "3";
BODY = "PICOPROBE_BXA","I66": #LOCATION = "J22" !CDS_LOCATION = "J22" &SEC = "1" #&CDS_SEC = "1";
"1_P":   PN = "1"  !CDS_PN = "1";
"2_N":   PN = "2"  !CDS_PN = "2";
"3_G":   PN = "3"  !CDS_PN = "3";
BODY = "PICOPROBE_BXA","I67": #LOCATION = "J30" !CDS_LOCATION = "J30" &SEC = "1" #&CDS_SEC = "1";
"1_P":   PN = "1"  !CDS_PN = "1";
"2_N":   PN = "2"  !CDS_PN = "2";
"3_G":   PN = "3"  !CDS_PN = "3";
BODY = "PICOPROBE_BXA","I68": #LOCATION = "J24" !CDS_LOCATION = "J24" &SEC = "1" #&CDS_SEC = "1";
"1_P":   PN = "1"  !CDS_PN = "1";
"2_N":   PN = "2"  !CDS_PN = "2";
"3_G":   PN = "3"  !CDS_PN = "3";
BODY = "PICOPROBE_BXA","I69": #LOCATION = "J23" !CDS_LOCATION = "J23" &SEC = "1" #&CDS_SEC = "1";
"1_P":   PN = "1"  !CDS_PN = "1";
"2_N":   PN = "2"  !CDS_PN = "2";
"3_G":   PN = "3"  !CDS_PN = "3";
BODY = "PICOPROBE_BXA","I70": #LOCATION = "J20" !CDS_LOCATION = "J20" &SEC = "1" #&CDS_SEC = "1";
"1_P":   PN = "1"  !CDS_PN = "1";
"2_N":   PN = "2"  !CDS_PN = "2";
"3_G":   PN = "3"  !CDS_PN = "3";
BODY = "PICOPROBE_BXA","I71": #LOCATION = "J19" !CDS_LOCATION = "J19" &SEC = "1" #&CDS_SEC = "1";
"1_P":   PN = "1"  !CDS_PN = "1";
"2_N":   PN = "2"  !CDS_PN = "2";
"3_G":   PN = "3"  !CDS_PN = "3";
END.
